FILE_TYPE = MACRO_DRAWING;
SET COLOR_WIRE YELLOW;
SET COLOR_PROP MONO;
SET COLOR_DOT WHITE;
SET COLOR_ARC YELLOW;
SET COLOR_BODY GREEN;
SET COLOR_NOTE MONO;
SET PROP_DISPLAY VALUE;
SET PAGE_NUMBER P79;
FORCEADD OFFPAGE..3
(1550 5150);
FORCEPROP 2 LAST $XR1 80 
J 0
(1854 5150);
DISPLAY 0.638298 (1854 5150);
PAINT MONO (1854 5150);
FORCEPROP 2 LAST $XR0 58 
J 0
(1764 5150);
DISPLAY 0.638298 (1764 5150);
PAINT MONO (1764 5150);
FORCEPROP 2 LAST CDS_LIB mstr_standard
J 0
(1550 5150);
DISPLAY 0.787234 (1550 5150);
PAINT MONO (1550 5150);
DISPLAY INVISIBLE (1550 5150);
FORCEPROP 1 LAST OFFPAGE TRUE
J 0
(1875 5025);
DISPLAY 0.936170 (1875 5025);
PAINT GREEN (1875 5025);
DISPLAY INVISIBLE (1875 5025);
FORCEPROP 1 LAST COMMENT_BODY TRUE
J 0
(1500 5050);
DISPLAY 0.936170 (1500 5050);
PAINT GREEN (1500 5050);
DISPLAY INVISIBLE (1500 5050);
FORCEPROP 2 LAST PATH I1
J 0
(1750 5225);
DISPLAY 0.787234 (1750 5225);
PAINT MONO (1750 5225);
DISPLAY INVISIBLE (1750 5225);
FORCEADD TAP..6
R 2
(650 4950);
FORCEPROP 3 LASTPIN (600 4950) SIG_NAME M_H_DQS_DP<15>
J 0
(610 4960);
DISPLAY 0.659574 (610 4960);
PAINT MONO (610 4960);
DISPLAY INVISIBLE (610 4960);
FORCEPROP 1 LASTPIN (600 4950) BN 15
J 2
(650 4960);
DISPLAY 0.617021 (650 4960);
PAINT PINK (650 4960);
FORCEPROP 2 LAST CDS_LIB mstr_standard
J 0
(650 4950);
DISPLAY 0.787234 (650 4950);
PAINT MONO (650 4950);
DISPLAY INVISIBLE (650 4950);
FORCEPROP 1 LAST BODY_TYPE PLUMBING
J 2
(650 4900);
DISPLAY 1.234043 (650 4900);
PAINT GREEN (650 4900);
DISPLAY INVISIBLE (650 4900);
FORCEPROP 1 LAST HDL_TAP TRUE
J 2
(325 4825);
DISPLAY 1.234043 (325 4825);
PAINT GREEN (325 4825);
DISPLAY INVISIBLE (325 4825);
FORCEPROP 1 LAST PATH I10
J 2
(650 4950);
DISPLAY 0.936170 (650 4950);
PAINT GREEN (650 4950);
DISPLAY INVISIBLE (650 4950);
FORCEADD TAP..6
R 2
(-1850 2000);
FORCEPROP 3 LASTPIN (-1900 2000) SIG_NAME M_H_DQ<4>
J 0
(-1890 2010);
DISPLAY 0.659574 (-1890 2010);
PAINT MONO (-1890 2010);
DISPLAY INVISIBLE (-1890 2010);
FORCEPROP 1 LASTPIN (-1900 2000) BN 4
J 2
(-1850 2010);
DISPLAY 0.617021 (-1850 2010);
PAINT PINK (-1850 2010);
FORCEPROP 2 LAST CDS_LIB mstr_standard
J 2
(-1850 2000);
DISPLAY 0.787234 (-1850 2000);
PAINT MONO (-1850 2000);
DISPLAY INVISIBLE (-1850 2000);
FORCEPROP 1 LAST BODY_TYPE PLUMBING
J 2
(-1850 1950);
DISPLAY 1.234043 (-1850 1950);
PAINT GREEN (-1850 1950);
DISPLAY INVISIBLE (-1850 1950);
FORCEPROP 1 LAST HDL_TAP TRUE
J 2
(-2175 1875);
DISPLAY 1.234043 (-2175 1875);
PAINT GREEN (-2175 1875);
DISPLAY INVISIBLE (-2175 1875);
FORCEPROP 1 LAST PATH I100
J 2
(-1850 2000);
DISPLAY 0.936170 (-1850 2000);
PAINT GREEN (-1850 2000);
DISPLAY INVISIBLE (-1850 2000);
FORCEADD TAP..6
R 2
(-1850 2100);
FORCEPROP 3 LASTPIN (-1900 2100) SIG_NAME M_H_DQ<6>
J 0
(-1890 2110);
DISPLAY 0.659574 (-1890 2110);
PAINT MONO (-1890 2110);
DISPLAY INVISIBLE (-1890 2110);
FORCEPROP 1 LASTPIN (-1900 2100) BN 6
J 2
(-1850 2110);
DISPLAY 0.617021 (-1850 2110);
PAINT PINK (-1850 2110);
FORCEPROP 2 LAST CDS_LIB mstr_standard
J 2
(-1850 2100);
DISPLAY 0.787234 (-1850 2100);
PAINT MONO (-1850 2100);
DISPLAY INVISIBLE (-1850 2100);
FORCEPROP 1 LAST BODY_TYPE PLUMBING
J 2
(-1850 2050);
DISPLAY 1.234043 (-1850 2050);
PAINT GREEN (-1850 2050);
DISPLAY INVISIBLE (-1850 2050);
FORCEPROP 1 LAST HDL_TAP TRUE
J 2
(-2175 1975);
DISPLAY 1.234043 (-2175 1975);
PAINT GREEN (-2175 1975);
DISPLAY INVISIBLE (-2175 1975);
FORCEPROP 1 LAST PATH I101
J 2
(-1850 2100);
DISPLAY 0.936170 (-1850 2100);
PAINT GREEN (-1850 2100);
DISPLAY INVISIBLE (-1850 2100);
FORCEADD TAP..6
R 2
(-1850 2050);
FORCEPROP 3 LASTPIN (-1900 2050) SIG_NAME M_H_DQ<7>
J 0
(-1890 2060);
DISPLAY 0.659574 (-1890 2060);
PAINT MONO (-1890 2060);
DISPLAY INVISIBLE (-1890 2060);
FORCEPROP 1 LASTPIN (-1900 2050) BN 7
J 2
(-1850 2060);
DISPLAY 0.617021 (-1850 2060);
PAINT PINK (-1850 2060);
FORCEPROP 2 LAST CDS_LIB mstr_standard
J 2
(-1850 2050);
DISPLAY 0.787234 (-1850 2050);
PAINT MONO (-1850 2050);
DISPLAY INVISIBLE (-1850 2050);
FORCEPROP 1 LAST BODY_TYPE PLUMBING
J 2
(-1850 2000);
DISPLAY 1.234043 (-1850 2000);
PAINT GREEN (-1850 2000);
DISPLAY INVISIBLE (-1850 2000);
FORCEPROP 1 LAST HDL_TAP TRUE
J 2
(-2175 1925);
DISPLAY 1.234043 (-2175 1925);
PAINT GREEN (-2175 1925);
DISPLAY INVISIBLE (-2175 1925);
FORCEPROP 1 LAST PATH I102
J 2
(-1850 2050);
DISPLAY 0.936170 (-1850 2050);
PAINT GREEN (-1850 2050);
DISPLAY INVISIBLE (-1850 2050);
FORCEADD TAP..6
R 2
(-1850 2150);
FORCEPROP 3 LASTPIN (-1900 2150) SIG_NAME M_H_DQ<9>
J 0
(-1890 2160);
DISPLAY 0.659574 (-1890 2160);
PAINT MONO (-1890 2160);
DISPLAY INVISIBLE (-1890 2160);
FORCEPROP 1 LASTPIN (-1900 2150) BN 9
J 2
(-1850 2160);
DISPLAY 0.617021 (-1850 2160);
PAINT PINK (-1850 2160);
FORCEPROP 2 LAST CDS_LIB mstr_standard
J 2
(-1850 2150);
DISPLAY 0.787234 (-1850 2150);
PAINT MONO (-1850 2150);
DISPLAY INVISIBLE (-1850 2150);
FORCEPROP 1 LAST BODY_TYPE PLUMBING
J 2
(-1850 2100);
DISPLAY 1.234043 (-1850 2100);
PAINT GREEN (-1850 2100);
DISPLAY INVISIBLE (-1850 2100);
FORCEPROP 1 LAST HDL_TAP TRUE
J 2
(-2175 2025);
DISPLAY 1.234043 (-2175 2025);
PAINT GREEN (-2175 2025);
DISPLAY INVISIBLE (-2175 2025);
FORCEPROP 1 LAST PATH I103
J 2
(-1850 2150);
DISPLAY 0.936170 (-1850 2150);
PAINT GREEN (-1850 2150);
DISPLAY INVISIBLE (-1850 2150);
FORCEADD TAP..6
R 2
(-1850 2200);
FORCEPROP 3 LASTPIN (-1900 2200) SIG_NAME M_H_DQ<8>
J 0
(-1890 2210);
DISPLAY 0.659574 (-1890 2210);
PAINT MONO (-1890 2210);
DISPLAY INVISIBLE (-1890 2210);
FORCEPROP 1 LASTPIN (-1900 2200) BN 8
J 2
(-1850 2210);
DISPLAY 0.617021 (-1850 2210);
PAINT PINK (-1850 2210);
FORCEPROP 2 LAST CDS_LIB mstr_standard
J 2
(-1850 2200);
DISPLAY 0.787234 (-1850 2200);
PAINT MONO (-1850 2200);
DISPLAY INVISIBLE (-1850 2200);
FORCEPROP 1 LAST BODY_TYPE PLUMBING
J 2
(-1850 2150);
DISPLAY 1.234043 (-1850 2150);
PAINT GREEN (-1850 2150);
DISPLAY INVISIBLE (-1850 2150);
FORCEPROP 1 LAST HDL_TAP TRUE
J 2
(-2175 2075);
DISPLAY 1.234043 (-2175 2075);
PAINT GREEN (-2175 2075);
DISPLAY INVISIBLE (-2175 2075);
FORCEPROP 1 LAST PATH I104
J 2
(-1850 2200);
DISPLAY 0.936170 (-1850 2200);
PAINT GREEN (-1850 2200);
DISPLAY INVISIBLE (-1850 2200);
FORCEADD TAP..6
R 2
(-1850 2250);
FORCEPROP 3 LASTPIN (-1900 2250) SIG_NAME M_H_DQ<11>
J 0
(-1890 2260);
DISPLAY 0.659574 (-1890 2260);
PAINT MONO (-1890 2260);
DISPLAY INVISIBLE (-1890 2260);
FORCEPROP 1 LASTPIN (-1900 2250) BN 11
J 2
(-1850 2260);
DISPLAY 0.617021 (-1850 2260);
PAINT PINK (-1850 2260);
FORCEPROP 2 LAST CDS_LIB mstr_standard
J 2
(-1850 2250);
DISPLAY 0.787234 (-1850 2250);
PAINT MONO (-1850 2250);
DISPLAY INVISIBLE (-1850 2250);
FORCEPROP 1 LAST BODY_TYPE PLUMBING
J 2
(-1850 2200);
DISPLAY 1.234043 (-1850 2200);
PAINT GREEN (-1850 2200);
DISPLAY INVISIBLE (-1850 2200);
FORCEPROP 1 LAST HDL_TAP TRUE
J 2
(-2175 2125);
DISPLAY 1.234043 (-2175 2125);
PAINT GREEN (-2175 2125);
DISPLAY INVISIBLE (-2175 2125);
FORCEPROP 1 LAST PATH I105
J 2
(-1850 2250);
DISPLAY 0.936170 (-1850 2250);
PAINT GREEN (-1850 2250);
DISPLAY INVISIBLE (-1850 2250);
FORCEADD TAP..6
R 2
(-1850 1900);
FORCEPROP 3 LASTPIN (-1900 1900) SIG_NAME M_H_DQ<2>
J 0
(-1890 1910);
DISPLAY 0.659574 (-1890 1910);
PAINT MONO (-1890 1910);
DISPLAY INVISIBLE (-1890 1910);
FORCEPROP 1 LASTPIN (-1900 1900) BN 2
J 2
(-1850 1910);
DISPLAY 0.617021 (-1850 1910);
PAINT PINK (-1850 1910);
FORCEPROP 2 LAST CDS_LIB mstr_standard
J 2
(-1850 1900);
DISPLAY 0.787234 (-1850 1900);
PAINT MONO (-1850 1900);
DISPLAY INVISIBLE (-1850 1900);
FORCEPROP 1 LAST BODY_TYPE PLUMBING
J 2
(-1850 1850);
DISPLAY 1.234043 (-1850 1850);
PAINT GREEN (-1850 1850);
DISPLAY INVISIBLE (-1850 1850);
FORCEPROP 1 LAST HDL_TAP TRUE
J 2
(-2175 1775);
DISPLAY 1.234043 (-2175 1775);
PAINT GREEN (-2175 1775);
DISPLAY INVISIBLE (-2175 1775);
FORCEPROP 1 LAST PATH I106
J 2
(-1850 1900);
DISPLAY 0.936170 (-1850 1900);
PAINT GREEN (-1850 1900);
DISPLAY INVISIBLE (-1850 1900);
FORCEADD TAP..6
R 2
(-1850 1950);
FORCEPROP 3 LASTPIN (-1900 1950) SIG_NAME M_H_DQ<5>
J 0
(-1890 1960);
DISPLAY 0.659574 (-1890 1960);
PAINT MONO (-1890 1960);
DISPLAY INVISIBLE (-1890 1960);
FORCEPROP 1 LASTPIN (-1900 1950) BN 5
J 2
(-1850 1960);
DISPLAY 0.617021 (-1850 1960);
PAINT PINK (-1850 1960);
FORCEPROP 2 LAST CDS_LIB mstr_standard
J 2
(-1850 1950);
DISPLAY 0.787234 (-1850 1950);
PAINT MONO (-1850 1950);
DISPLAY INVISIBLE (-1850 1950);
FORCEPROP 1 LAST BODY_TYPE PLUMBING
J 2
(-1850 1900);
DISPLAY 1.234043 (-1850 1900);
PAINT GREEN (-1850 1900);
DISPLAY INVISIBLE (-1850 1900);
FORCEPROP 1 LAST HDL_TAP TRUE
J 2
(-2175 1825);
DISPLAY 1.234043 (-2175 1825);
PAINT GREEN (-2175 1825);
DISPLAY INVISIBLE (-2175 1825);
FORCEPROP 1 LAST PATH I107
J 2
(-1850 1950);
DISPLAY 0.936170 (-1850 1950);
PAINT GREEN (-1850 1950);
DISPLAY INVISIBLE (-1850 1950);
FORCEADD TAP..6
R 2
(-1850 1800);
FORCEPROP 3 LASTPIN (-1900 1800) SIG_NAME M_H_DQ<0>
J 0
(-1890 1810);
DISPLAY 0.659574 (-1890 1810);
PAINT MONO (-1890 1810);
DISPLAY INVISIBLE (-1890 1810);
FORCEPROP 1 LASTPIN (-1900 1800) BN 0
J 2
(-1850 1810);
DISPLAY 0.617021 (-1850 1810);
PAINT PINK (-1850 1810);
FORCEPROP 2 LAST CDS_LIB mstr_standard
J 2
(-1850 1800);
DISPLAY 0.787234 (-1850 1800);
PAINT MONO (-1850 1800);
DISPLAY INVISIBLE (-1850 1800);
FORCEPROP 1 LAST BODY_TYPE PLUMBING
J 2
(-1850 1750);
DISPLAY 1.234043 (-1850 1750);
PAINT GREEN (-1850 1750);
DISPLAY INVISIBLE (-1850 1750);
FORCEPROP 1 LAST HDL_TAP TRUE
J 2
(-2175 1675);
DISPLAY 1.234043 (-2175 1675);
PAINT GREEN (-2175 1675);
DISPLAY INVISIBLE (-2175 1675);
FORCEPROP 1 LAST PATH I108
J 2
(-1850 1800);
DISPLAY 0.936170 (-1850 1800);
PAINT GREEN (-1850 1800);
DISPLAY INVISIBLE (-1850 1800);
FORCEADD TAP..6
R 2
(-1850 1750);
FORCEPROP 3 LASTPIN (-1900 1750) SIG_NAME M_H_DQ<1>
J 0
(-1890 1760);
DISPLAY 0.659574 (-1890 1760);
PAINT MONO (-1890 1760);
DISPLAY INVISIBLE (-1890 1760);
FORCEPROP 1 LASTPIN (-1900 1750) BN 1
J 2
(-1850 1760);
DISPLAY 0.617021 (-1850 1760);
PAINT PINK (-1850 1760);
FORCEPROP 2 LAST CDS_LIB mstr_standard
J 2
(-1850 1750);
DISPLAY 0.787234 (-1850 1750);
PAINT MONO (-1850 1750);
DISPLAY INVISIBLE (-1850 1750);
FORCEPROP 1 LAST BODY_TYPE PLUMBING
J 2
(-1850 1700);
DISPLAY 1.234043 (-1850 1700);
PAINT GREEN (-1850 1700);
DISPLAY INVISIBLE (-1850 1700);
FORCEPROP 1 LAST HDL_TAP TRUE
J 2
(-2175 1625);
DISPLAY 1.234043 (-2175 1625);
PAINT GREEN (-2175 1625);
DISPLAY INVISIBLE (-2175 1625);
FORCEPROP 1 LAST PATH I109
J 2
(-1850 1750);
DISPLAY 0.936170 (-1850 1750);
PAINT GREEN (-1850 1750);
DISPLAY INVISIBLE (-1850 1750);
FORCEADD TAP..6
R 2
(650 4850);
FORCEPROP 3 LASTPIN (600 4850) SIG_NAME M_H_DQS_DP<14>
J 0
(610 4860);
DISPLAY 0.659574 (610 4860);
PAINT MONO (610 4860);
DISPLAY INVISIBLE (610 4860);
FORCEPROP 1 LASTPIN (600 4850) BN 14
J 2
(650 4860);
DISPLAY 0.617021 (650 4860);
PAINT PINK (650 4860);
FORCEPROP 2 LAST CDS_LIB mstr_standard
J 0
(650 4850);
DISPLAY 0.787234 (650 4850);
PAINT MONO (650 4850);
DISPLAY INVISIBLE (650 4850);
FORCEPROP 1 LAST BODY_TYPE PLUMBING
J 2
(650 4800);
DISPLAY 1.234043 (650 4800);
PAINT GREEN (650 4800);
DISPLAY INVISIBLE (650 4800);
FORCEPROP 1 LAST HDL_TAP TRUE
J 2
(325 4725);
DISPLAY 1.234043 (325 4725);
PAINT GREEN (325 4725);
DISPLAY INVISIBLE (325 4725);
FORCEPROP 1 LAST PATH I11
J 2
(650 4850);
DISPLAY 0.936170 (650 4850);
PAINT GREEN (650 4850);
DISPLAY INVISIBLE (650 4850);
FORCEADD TAP..6
R 2
(-1850 1850);
FORCEPROP 3 LASTPIN (-1900 1850) SIG_NAME M_H_DQ<3>
J 0
(-1890 1860);
DISPLAY 0.659574 (-1890 1860);
PAINT MONO (-1890 1860);
DISPLAY INVISIBLE (-1890 1860);
FORCEPROP 1 LASTPIN (-1900 1850) BN 3
J 2
(-1850 1860);
DISPLAY 0.617021 (-1850 1860);
PAINT PINK (-1850 1860);
FORCEPROP 2 LAST CDS_LIB mstr_standard
J 2
(-1850 1850);
DISPLAY 0.787234 (-1850 1850);
PAINT MONO (-1850 1850);
DISPLAY INVISIBLE (-1850 1850);
FORCEPROP 1 LAST BODY_TYPE PLUMBING
J 2
(-1850 1800);
DISPLAY 1.234043 (-1850 1800);
PAINT GREEN (-1850 1800);
DISPLAY INVISIBLE (-1850 1800);
FORCEPROP 1 LAST HDL_TAP TRUE
J 2
(-2175 1725);
DISPLAY 1.234043 (-2175 1725);
PAINT GREEN (-2175 1725);
DISPLAY INVISIBLE (-2175 1725);
FORCEPROP 1 LAST PATH I110
J 2
(-1850 1850);
DISPLAY 0.936170 (-1850 1850);
PAINT GREEN (-1850 1850);
DISPLAY INVISIBLE (-1850 1850);
FORCEADD SCONN288_H44441004..1
(-2600 3250);
FORCEPROP 2 LASTPIN (-3100 2100) $PN 284
J 2
(-3110 2110);
DISPLAY 0.617021 (-3110 2110);
PAINT ORANGE (-3110 2110);
FORCEPROP 1 LAST LOCATION J1G2
J 0
(-3050 5150);
DISPLAY 0.617021 (-3050 5150);
PAINT AQUA (-3050 5150);
FORCEPROP 1 LAST PART_NUMBER H44441-004
J 0
(-3050 1250);
DISPLAY 0.617021 (-3050 1250);
PAINT BLUE (-3050 1250);
FORCEPROP 1 LAST MATERIAL SCONN
J 0
(-3050 5100);
DISPLAY 0.617021 (-3050 5100);
PAINT SKYBLUE (-3050 5100);
FORCEPROP 2 LASTPIN (-3100 1750) $PN 146
J 2
(-3110 1760);
DISPLAY 0.617021 (-3110 1760);
PAINT ORANGE (-3110 1760);
FORCEPROP 2 LASTPIN (-3100 1900) $PN 285
J 2
(-3110 1910);
DISPLAY 0.617021 (-3110 1910);
PAINT ORANGE (-3110 1910);
FORCEPROP 2 LASTPIN (-3100 1850) $PN 141
J 2
(-3110 1860);
DISPLAY 0.617021 (-3110 1860);
PAINT ORANGE (-3110 1860);
FORCEPROP 2 LASTPIN (-3100 1450) $PN 230
J 2
(-3110 1460);
DISPLAY 0.617021 (-3110 1460);
PAINT ORANGE (-3110 1460);
FORCEPROP 2 LASTPIN (-3100 2050) $PN 238
J 2
(-3110 2060);
DISPLAY 0.617021 (-3110 2060);
PAINT ORANGE (-3110 2060);
FORCEPROP 2 LASTPIN (-3100 2000) $PN 140
J 2
(-3110 2010);
DISPLAY 0.617021 (-3110 2010);
PAINT ORANGE (-3110 2010);
FORCEPROP 2 LASTPIN (-3100 1950) $PN 139
J 2
(-3110 1960);
DISPLAY 0.617021 (-3110 1960);
PAINT ORANGE (-3110 1960);
FORCEPROP 2 LASTPIN (-3100 3400) $PN 237
J 2
(-3110 3410);
DISPLAY 0.617021 (-3110 3410);
PAINT ORANGE (-3110 3410);
FORCEPROP 2 LASTPIN (-3100 3350) $PN 93
J 2
(-3110 3360);
DISPLAY 0.617021 (-3110 3360);
PAINT ORANGE (-3110 3360);
FORCEPROP 2 LASTPIN (-3100 3300) $PN 89
J 2
(-3110 3310);
DISPLAY 0.617021 (-3110 3310);
PAINT ORANGE (-3110 3310);
FORCEPROP 2 LASTPIN (-3100 3250) $PN 84
J 2
(-3110 3260);
DISPLAY 0.617021 (-3110 3260);
PAINT ORANGE (-3110 3260);
FORCEPROP 2 LASTPIN (-3100 1650) $PN 144
J 2
(-3110 1660);
DISPLAY 0.617021 (-3110 1660);
PAINT ORANGE (-3110 1660);
FORCEPROP 2 LASTPIN (-3100 1600) $PN 227
J 2
(-3110 1610);
DISPLAY 0.617021 (-3110 1610);
PAINT ORANGE (-3110 1610);
FORCEPROP 2 LASTPIN (-3100 1550) $PN 205
J 2
(-3110 1560);
DISPLAY 0.617021 (-3110 1560);
PAINT ORANGE (-3110 1560);
FORCEPROP 2 LASTPIN (-3100 2350) $PN 58
J 2
(-3110 2360);
DISPLAY 0.617021 (-3110 2360);
PAINT ORANGE (-3110 2360);
FORCEPROP 2 LASTPIN (-3100 2400) $PN 222
J 2
(-3110 2410);
DISPLAY 0.617021 (-3110 2410);
PAINT ORANGE (-3110 2410);
FORCEPROP 2 LASTPIN (-3100 3000) $PN 91
J 2
(-3110 3010);
DISPLAY 0.617021 (-3110 3010);
PAINT ORANGE (-3110 3010);
FORCEPROP 2 LASTPIN (-3100 2950) $PN 87
J 2
(-3110 2960);
DISPLAY 0.617021 (-3110 2960);
PAINT ORANGE (-3110 2960);
FORCEPROP 2 LASTPIN (-3100 2300) $PN 78
J 2
(-3110 2310);
DISPLAY 0.617021 (-3110 2310);
PAINT ORANGE (-3110 2310);
FORCEPROP 2 LASTPIN (-2100 4900) $PN 280
J 0
(-2090 4910);
DISPLAY 0.617021 (-2090 4910);
PAINT ORANGE (-2090 4910);
FORCEPROP 2 LASTPIN (-2100 4850) $PN 135
J 0
(-2090 4860);
DISPLAY 0.617021 (-2090 4860);
PAINT ORANGE (-2090 4860);
FORCEPROP 2 LASTPIN (-2100 4800) $PN 273
J 0
(-2090 4810);
DISPLAY 0.617021 (-2090 4810);
PAINT ORANGE (-2090 4810);
FORCEPROP 2 LASTPIN (-2100 4750) $PN 128
J 0
(-2090 4760);
DISPLAY 0.617021 (-2090 4760);
PAINT ORANGE (-2090 4760);
FORCEPROP 2 LASTPIN (-2100 4550) $PN 130
J 0
(-2090 4560);
DISPLAY 0.617021 (-2090 4560);
PAINT ORANGE (-2090 4560);
FORCEPROP 2 LASTPIN (-2100 4500) $PN 269
J 0
(-2090 4510);
DISPLAY 0.617021 (-2090 4510);
PAINT ORANGE (-2090 4510);
FORCEPROP 2 LASTPIN (-2100 4450) $PN 124
J 0
(-2090 4460);
DISPLAY 0.617021 (-2090 4460);
PAINT ORANGE (-2090 4460);
FORCEPROP 2 LASTPIN (-2100 4300) $PN 271
J 0
(-2090 4310);
DISPLAY 0.617021 (-2090 4310);
PAINT ORANGE (-2090 4310);
FORCEPROP 2 LASTPIN (-2100 4250) $PN 126
J 0
(-2090 4260);
DISPLAY 0.617021 (-2090 4260);
PAINT ORANGE (-2090 4260);
FORCEPROP 2 LASTPIN (-2100 4200) $PN 264
J 0
(-2090 4210);
DISPLAY 0.617021 (-2090 4210);
PAINT ORANGE (-2090 4210);
FORCEPROP 2 LASTPIN (-2100 4150) $PN 119
J 0
(-2090 4160);
DISPLAY 0.617021 (-2090 4160);
PAINT ORANGE (-2090 4160);
FORCEPROP 2 LASTPIN (-2100 4100) $PN 258
J 0
(-2090 4110);
DISPLAY 0.617021 (-2090 4110);
PAINT ORANGE (-2090 4110);
FORCEPROP 2 LASTPIN (-2100 4050) $PN 113
J 0
(-2090 4060);
DISPLAY 0.617021 (-2090 4060);
PAINT ORANGE (-2090 4060);
FORCEPROP 2 LASTPIN (-2100 4000) $PN 251
J 0
(-2090 4010);
DISPLAY 0.617021 (-2090 4010);
PAINT ORANGE (-2090 4010);
FORCEPROP 2 LASTPIN (-2100 3950) $PN 106
J 0
(-2090 3960);
DISPLAY 0.617021 (-2090 3960);
PAINT ORANGE (-2090 3960);
FORCEPROP 2 LASTPIN (-2100 3900) $PN 260
J 0
(-2090 3910);
DISPLAY 0.617021 (-2090 3910);
PAINT ORANGE (-2090 3910);
FORCEPROP 2 LASTPIN (-2100 3850) $PN 115
J 0
(-2090 3860);
DISPLAY 0.617021 (-2090 3860);
PAINT ORANGE (-2090 3860);
FORCEPROP 2 LASTPIN (-2100 3800) $PN 253
J 0
(-2090 3810);
DISPLAY 0.617021 (-2090 3810);
PAINT ORANGE (-2090 3810);
FORCEPROP 2 LASTPIN (-2100 3750) $PN 108
J 0
(-2090 3760);
DISPLAY 0.617021 (-2090 3760);
PAINT ORANGE (-2090 3760);
FORCEPROP 2 LASTPIN (-2100 3700) $PN 247
J 0
(-2090 3710);
DISPLAY 0.617021 (-2090 3710);
PAINT ORANGE (-2090 3710);
FORCEPROP 2 LASTPIN (-2100 3650) $PN 102
J 0
(-2090 3660);
DISPLAY 0.617021 (-2090 3660);
PAINT ORANGE (-2090 3660);
FORCEPROP 2 LASTPIN (-2100 3600) $PN 240
J 0
(-2090 3610);
DISPLAY 0.617021 (-2090 3610);
PAINT ORANGE (-2090 3610);
FORCEPROP 2 LASTPIN (-2100 3550) $PN 95
J 0
(-2090 3560);
DISPLAY 0.617021 (-2090 3560);
PAINT ORANGE (-2090 3560);
FORCEPROP 2 LASTPIN (-2100 3500) $PN 249
J 0
(-2090 3510);
DISPLAY 0.617021 (-2090 3510);
PAINT ORANGE (-2090 3510);
FORCEPROP 2 LASTPIN (-2100 3450) $PN 104
J 0
(-2090 3460);
DISPLAY 0.617021 (-2090 3460);
PAINT ORANGE (-2090 3460);
FORCEPROP 2 LASTPIN (-2100 3400) $PN 242
J 0
(-2090 3410);
DISPLAY 0.617021 (-2090 3410);
PAINT ORANGE (-2090 3410);
FORCEPROP 2 LASTPIN (-2100 3350) $PN 97
J 0
(-2090 3360);
DISPLAY 0.617021 (-2090 3360);
PAINT ORANGE (-2090 3360);
FORCEPROP 2 LASTPIN (-2100 3300) $PN 188
J 0
(-2090 3310);
DISPLAY 0.617021 (-2090 3310);
PAINT ORANGE (-2090 3310);
FORCEPROP 2 LASTPIN (-2100 3200) $PN 181
J 0
(-2090 3210);
DISPLAY 0.617021 (-2090 3210);
PAINT ORANGE (-2090 3210);
FORCEPROP 2 LASTPIN (-2100 3150) $PN 36
J 0
(-2090 3160);
DISPLAY 0.617021 (-2090 3160);
PAINT ORANGE (-2090 3160);
FORCEPROP 2 LASTPIN (-2100 3100) $PN 190
J 0
(-2090 3110);
DISPLAY 0.617021 (-2090 3110);
PAINT ORANGE (-2090 3110);
FORCEPROP 2 LASTPIN (-2100 3050) $PN 45
J 0
(-2090 3060);
DISPLAY 0.617021 (-2090 3060);
PAINT ORANGE (-2090 3060);
FORCEPROP 2 LASTPIN (-2100 3000) $PN 183
J 0
(-2090 3010);
DISPLAY 0.617021 (-2090 3010);
PAINT ORANGE (-2090 3010);
FORCEPROP 2 LASTPIN (-2100 2950) $PN 38
J 0
(-2090 2960);
DISPLAY 0.617021 (-2090 2960);
PAINT ORANGE (-2090 2960);
FORCEPROP 2 LASTPIN (-2100 2900) $PN 177
J 0
(-2090 2910);
DISPLAY 0.617021 (-2090 2910);
PAINT ORANGE (-2090 2910);
FORCEPROP 2 LASTPIN (-2100 2850) $PN 32
J 0
(-2090 2860);
DISPLAY 0.617021 (-2090 2860);
PAINT ORANGE (-2090 2860);
FORCEPROP 2 LASTPIN (-2100 2800) $PN 170
J 0
(-2090 2810);
DISPLAY 0.617021 (-2090 2810);
PAINT ORANGE (-2090 2810);
FORCEPROP 2 LASTPIN (-2100 2750) $PN 25
J 0
(-2090 2760);
DISPLAY 0.617021 (-2090 2760);
PAINT ORANGE (-2090 2760);
FORCEPROP 2 LASTPIN (-2100 2700) $PN 179
J 0
(-2090 2710);
DISPLAY 0.617021 (-2090 2710);
PAINT ORANGE (-2090 2710);
FORCEPROP 2 LASTPIN (-2100 2650) $PN 34
J 0
(-2090 2660);
DISPLAY 0.617021 (-2090 2660);
PAINT ORANGE (-2090 2660);
FORCEPROP 2 LASTPIN (-2100 2600) $PN 172
J 0
(-2090 2610);
DISPLAY 0.617021 (-2090 2610);
PAINT ORANGE (-2090 2610);
FORCEPROP 2 LASTPIN (-2100 2550) $PN 27
J 0
(-2090 2560);
DISPLAY 0.617021 (-2090 2560);
PAINT ORANGE (-2090 2560);
FORCEPROP 2 LASTPIN (-2100 2500) $PN 166
J 0
(-2090 2510);
DISPLAY 0.617021 (-2090 2510);
PAINT ORANGE (-2090 2510);
FORCEPROP 2 LASTPIN (-2100 2450) $PN 21
J 0
(-2090 2460);
DISPLAY 0.617021 (-2090 2460);
PAINT ORANGE (-2090 2460);
FORCEPROP 2 LASTPIN (-2100 2400) $PN 159
J 0
(-2090 2410);
DISPLAY 0.617021 (-2090 2410);
PAINT ORANGE (-2090 2410);
FORCEPROP 2 LASTPIN (-2100 2350) $PN 14
J 0
(-2090 2360);
DISPLAY 0.617021 (-2090 2360);
PAINT ORANGE (-2090 2360);
FORCEPROP 2 LASTPIN (-2100 2300) $PN 168
J 0
(-2090 2310);
DISPLAY 0.617021 (-2090 2310);
PAINT ORANGE (-2090 2310);
FORCEPROP 2 LASTPIN (-2100 2250) $PN 23
J 0
(-2090 2260);
DISPLAY 0.617021 (-2090 2260);
PAINT ORANGE (-2090 2260);
FORCEPROP 2 LASTPIN (-2100 2200) $PN 161
J 0
(-2090 2210);
DISPLAY 0.617021 (-2090 2210);
PAINT ORANGE (-2090 2210);
FORCEPROP 2 LASTPIN (-2100 2150) $PN 16
J 0
(-2090 2160);
DISPLAY 0.617021 (-2090 2160);
PAINT ORANGE (-2090 2160);
FORCEPROP 2 LASTPIN (-2100 2100) $PN 155
J 0
(-2090 2110);
DISPLAY 0.617021 (-2090 2110);
PAINT ORANGE (-2090 2110);
FORCEPROP 2 LASTPIN (-2100 2050) $PN 10
J 0
(-2090 2060);
DISPLAY 0.617021 (-2090 2060);
PAINT ORANGE (-2090 2060);
FORCEPROP 2 LASTPIN (-2100 2000) $PN 148
J 0
(-2090 2010);
DISPLAY 0.617021 (-2090 2010);
PAINT ORANGE (-2090 2010);
FORCEPROP 2 LASTPIN (-2100 1950) $PN 3
J 0
(-2090 1960);
DISPLAY 0.617021 (-2090 1960);
PAINT ORANGE (-2090 1960);
FORCEPROP 2 LASTPIN (-2100 1900) $PN 157
J 0
(-2090 1910);
DISPLAY 0.617021 (-2090 1910);
PAINT ORANGE (-2090 1910);
FORCEPROP 2 LASTPIN (-2100 1850) $PN 12
J 0
(-2090 1860);
DISPLAY 0.617021 (-2090 1860);
PAINT ORANGE (-2090 1860);
FORCEPROP 2 LASTPIN (-2100 1800) $PN 150
J 0
(-2090 1810);
DISPLAY 0.617021 (-2090 1810);
PAINT ORANGE (-2090 1810);
FORCEPROP 2 LASTPIN (-2100 1750) $PN 5
J 0
(-2090 1760);
DISPLAY 0.617021 (-2090 1760);
PAINT ORANGE (-2090 1760);
FORCEPROP 2 LASTPIN (-3100 3150) $PN 203
J 2
(-3110 3160);
DISPLAY 0.617021 (-3110 3160);
PAINT ORANGE (-3110 3160);
FORCEPROP 2 LASTPIN (-3100 3100) $PN 60
J 2
(-3110 3110);
DISPLAY 0.617021 (-3110 3110);
PAINT ORANGE (-3110 3110);
FORCEPROP 2 LASTPIN (-3100 3700) $PN 218
J 2
(-3110 3710);
DISPLAY 0.617021 (-3110 3710);
PAINT ORANGE (-3110 3710);
FORCEPROP 2 LASTPIN (-3100 3650) $PN 219
J 2
(-3110 3660);
DISPLAY 0.617021 (-3110 3660);
PAINT ORANGE (-3110 3660);
FORCEPROP 2 LASTPIN (-3100 3600) $PN 74
J 2
(-3110 3610);
DISPLAY 0.617021 (-3110 3610);
PAINT ORANGE (-3110 3610);
FORCEPROP 2 LASTPIN (-3100 3550) $PN 75
J 2
(-3110 3560);
DISPLAY 0.617021 (-3110 3560);
PAINT ORANGE (-3110 3560);
FORCEPROP 2 LASTPIN (-3100 2850) $PN 199
J 2
(-3110 2860);
DISPLAY 0.617021 (-3110 2860);
PAINT ORANGE (-3110 2860);
FORCEPROP 2 LASTPIN (-3100 2800) $PN 54
J 2
(-3110 2810);
DISPLAY 0.617021 (-3110 2810);
PAINT ORANGE (-3110 2810);
FORCEPROP 2 LASTPIN (-3100 2750) $PN 192
J 2
(-3110 2760);
DISPLAY 0.617021 (-3110 2760);
PAINT ORANGE (-3110 2760);
FORCEPROP 2 LASTPIN (-3100 2700) $PN 47
J 2
(-3110 2710);
DISPLAY 0.617021 (-3110 2710);
PAINT ORANGE (-3110 2710);
FORCEPROP 2 LASTPIN (-3100 2650) $PN 201
J 2
(-3110 2660);
DISPLAY 0.617021 (-3110 2660);
PAINT ORANGE (-3110 2660);
FORCEPROP 2 LASTPIN (-3100 2600) $PN 56
J 2
(-3110 2610);
DISPLAY 0.617021 (-3110 2610);
PAINT ORANGE (-3110 2610);
FORCEPROP 2 LASTPIN (-3100 2550) $PN 194
J 2
(-3110 2560);
DISPLAY 0.617021 (-3110 2560);
PAINT ORANGE (-3110 2560);
FORCEPROP 2 LASTPIN (-3100 2500) $PN 49
J 2
(-3110 2510);
DISPLAY 0.617021 (-3110 2510);
PAINT ORANGE (-3110 2510);
FORCEPROP 2 LASTPIN (-3100 3450) $PN 235
J 2
(-3110 3460);
DISPLAY 0.617021 (-3110 3460);
PAINT ORANGE (-3110 3460);
FORCEPROP 2 LASTPIN (-3100 3850) $PN 207
J 2
(-3110 3860);
DISPLAY 0.617021 (-3110 3860);
PAINT ORANGE (-3110 3860);
FORCEPROP 2 LASTPIN (-3100 3800) $PN 63
J 2
(-3110 3810);
DISPLAY 0.617021 (-3110 3810);
PAINT ORANGE (-3110 3810);
FORCEPROP 2 LASTPIN (-3100 3950) $PN 224
J 2
(-3110 3960);
DISPLAY 0.617021 (-3110 3960);
PAINT ORANGE (-3110 3960);
FORCEPROP 2 LASTPIN (-3100 3900) $PN 81
J 2
(-3110 3910);
DISPLAY 0.617021 (-3110 3910);
PAINT ORANGE (-3110 3910);
FORCEPROP 2 LASTPIN (-3100 2250) $PN 208
J 2
(-3110 2260);
DISPLAY 0.617021 (-3110 2260);
PAINT ORANGE (-3110 2260);
FORCEPROP 2 LASTPIN (-3100 2200) $PN 62
J 2
(-3110 2210);
DISPLAY 0.617021 (-3110 2210);
PAINT ORANGE (-3110 2210);
FORCEPROP 2 LASTPIN (-3100 4900) $PN 234
J 2
(-3110 4910);
DISPLAY 0.617021 (-3110 4910);
PAINT ORANGE (-3110 4910);
FORCEPROP 2 LASTPIN (-3100 4850) $PN 82
J 2
(-3110 4860);
DISPLAY 0.617021 (-3110 4860);
PAINT ORANGE (-3110 4860);
FORCEPROP 2 LASTPIN (-3100 4800) $PN 86
J 2
(-3110 4810);
DISPLAY 0.617021 (-3110 4810);
PAINT ORANGE (-3110 4810);
FORCEPROP 2 LASTPIN (-3100 4750) $PN 228
J 2
(-3110 4760);
DISPLAY 0.617021 (-3110 4760);
PAINT ORANGE (-3110 4760);
FORCEPROP 2 LASTPIN (-3100 4700) $PN 232
J 2
(-3110 4710);
DISPLAY 0.617021 (-3110 4710);
PAINT ORANGE (-3110 4710);
FORCEPROP 2 LASTPIN (-3100 4650) $PN 65
J 2
(-3110 4660);
DISPLAY 0.617021 (-3110 4660);
PAINT ORANGE (-3110 4660);
FORCEPROP 2 LASTPIN (-3100 4600) $PN 210
J 2
(-3110 4610);
DISPLAY 0.617021 (-3110 4610);
PAINT ORANGE (-3110 4610);
FORCEPROP 2 LASTPIN (-3100 4550) $PN 225
J 2
(-3110 4560);
DISPLAY 0.617021 (-3110 4560);
PAINT ORANGE (-3110 4560);
FORCEPROP 2 LASTPIN (-3100 4500) $PN 66
J 2
(-3110 4510);
DISPLAY 0.617021 (-3110 4510);
PAINT ORANGE (-3110 4510);
FORCEPROP 2 LASTPIN (-3100 4450) $PN 68
J 2
(-3110 4460);
DISPLAY 0.617021 (-3110 4460);
PAINT ORANGE (-3110 4460);
FORCEPROP 2 LASTPIN (-3100 4400) $PN 211
J 2
(-3110 4410);
DISPLAY 0.617021 (-3110 4410);
PAINT ORANGE (-3110 4410);
FORCEPROP 2 LASTPIN (-3100 4350) $PN 69
J 2
(-3110 4360);
DISPLAY 0.617021 (-3110 4360);
PAINT ORANGE (-3110 4360);
FORCEPROP 2 LASTPIN (-3100 4300) $PN 213
J 2
(-3110 4310);
DISPLAY 0.617021 (-3110 4310);
PAINT ORANGE (-3110 4310);
FORCEPROP 2 LASTPIN (-3100 4250) $PN 214
J 2
(-3110 4260);
DISPLAY 0.617021 (-3110 4260);
PAINT ORANGE (-3110 4260);
FORCEPROP 2 LASTPIN (-3100 4200) $PN 71
J 2
(-3110 4210);
DISPLAY 0.617021 (-3110 4210);
PAINT ORANGE (-3110 4210);
FORCEPROP 2 LASTPIN (-3100 4150) $PN 216
J 2
(-3110 4160);
DISPLAY 0.617021 (-3110 4160);
PAINT ORANGE (-3110 4160);
FORCEPROP 2 LASTPIN (-3100 4100) $PN 72
J 2
(-3110 4110);
DISPLAY 0.617021 (-3110 4110);
PAINT ORANGE (-3110 4110);
FORCEPROP 2 LASTPIN (-3100 4050) $PN 79
J 2
(-3110 4060);
DISPLAY 0.617021 (-3110 4060);
PAINT ORANGE (-3110 4060);
FORCEPROP 2 LASTPIN (-2100 4400) $PN 262
J 0
(-2090 4410);
DISPLAY 0.617021 (-2090 4410);
PAINT ORANGE (-2090 4410);
FORCEPROP 2 LASTPIN (-2100 4350) $PN 117
J 0
(-2090 4360);
DISPLAY 0.617021 (-2090 4360);
PAINT ORANGE (-2090 4360);
FORCEPROP 2 LASTPIN (-2100 3250) $PN 43
J 0
(-2090 3260);
DISPLAY 0.617021 (-2090 3260);
PAINT ORANGE (-2090 3260);
FORCEPROP 2 LASTPIN (-2100 4600) $PN 275
J 0
(-2090 4610);
DISPLAY 0.617021 (-2090 4610);
PAINT ORANGE (-2090 4610);
FORCEPROP 2 LASTPIN (-2100 4650) $PN 137
J 0
(-2090 4660);
DISPLAY 0.617021 (-2090 4660);
PAINT ORANGE (-2090 4660);
FORCEPROP 2 LASTPIN (-2100 4700) $PN 282
J 0
(-2090 4710);
DISPLAY 0.617021 (-2090 4710);
PAINT ORANGE (-2090 4710);
FORCEPROP 1 LAST PACK_TYPE PIP
J 0
(-3050 5200);
PAINT SKYBLUE (-3050 5200);
DISPLAY INVISIBLE (-3050 5200);
FORCEPROP 2 LAST BOM_COST MEM
J 0
(-2600 3250);
PAINT ORANGE (-2600 3250);
DISPLAY INVISIBLE (-2600 3250);
FORCEPROP 2 LAST CDS_LIB mstr_sconn
J 0
(-2600 3250);
PAINT ORANGE (-2600 3250);
DISPLAY INVISIBLE (-2600 3250);
FORCEPROP 2 LAST SEC_TYPE PIP
J 0
(-3050 5200);
DISPLAY 1.021277 (-3050 5200);
PAINT ORANGE (-3050 5200);
DISPLAY INVISIBLE (-3050 5200);
FORCEPROP 2 LAST SEC 1
J 0
(-3050 5200);
DISPLAY 0.680851 (-3050 5200);
PAINT MONO (-3050 5200);
DISPLAY INVISIBLE (-3050 5200);
FORCEPROP 2 LAST CDS_LOCATION J1G2
J 0
(-3050 5150);
DISPLAY 0.617021 (-3050 5150);
PAINT AQUA (-3050 5150);
DISPLAY INVISIBLE (-3050 5150);
FORCEPROP 1 LAST PATH I111
J 0
(-2600 5100);
PAINT GREEN (-2600 5100);
DISPLAY INVISIBLE (-2600 5100);
FORCEPROP 2 LAST ROOM DDR4_CH_H
J 0
(-2600 3250);
PAINT ORANGE (-2600 3250);
DISPLAY INVISIBLE (-2600 3250);
FORCEADD TAP..6
(-3350 4850);
FORCEPROP 3 LASTPIN (-3300 4850) SIG_NAME M_H_MA<16>
J 0
(-3290 4860);
DISPLAY 0.659574 (-3290 4860);
PAINT MONO (-3290 4860);
DISPLAY INVISIBLE (-3290 4860);
FORCEPROP 1 LASTPIN (-3300 4850) BN 16
J 0
(-3350 4860);
DISPLAY 0.617021 (-3350 4860);
PAINT PINK (-3350 4860);
FORCEPROP 2 LAST CDS_LIB mstr_standard
J 2
(-3350 4850);
DISPLAY 0.787234 (-3350 4850);
PAINT MONO (-3350 4850);
DISPLAY INVISIBLE (-3350 4850);
FORCEPROP 1 LAST BODY_TYPE PLUMBING
J 0
(-3350 4800);
DISPLAY 1.234043 (-3350 4800);
PAINT GREEN (-3350 4800);
DISPLAY INVISIBLE (-3350 4800);
FORCEPROP 1 LAST HDL_TAP TRUE
J 0
(-3025 4725);
DISPLAY 1.234043 (-3025 4725);
PAINT GREEN (-3025 4725);
DISPLAY INVISIBLE (-3025 4725);
FORCEPROP 1 LAST PATH I112
J 0
(-3350 4850);
DISPLAY 0.936170 (-3350 4850);
PAINT GREEN (-3350 4850);
DISPLAY INVISIBLE (-3350 4850);
FORCEADD TAP..6
(-3350 4900);
FORCEPROP 3 LASTPIN (-3300 4900) SIG_NAME M_H_MA<17>
J 0
(-3290 4910);
DISPLAY 0.659574 (-3290 4910);
PAINT MONO (-3290 4910);
DISPLAY INVISIBLE (-3290 4910);
FORCEPROP 1 LASTPIN (-3300 4900) BN 17
J 0
(-3350 4910);
DISPLAY 0.617021 (-3350 4910);
PAINT PINK (-3350 4910);
FORCEPROP 2 LAST CDS_LIB mstr_standard
J 0
(-3350 4900);
DISPLAY 0.787234 (-3350 4900);
PAINT MONO (-3350 4900);
DISPLAY INVISIBLE (-3350 4900);
FORCEPROP 1 LAST BODY_TYPE PLUMBING
J 0
(-3350 4850);
DISPLAY 1.234043 (-3350 4850);
PAINT GREEN (-3350 4850);
DISPLAY INVISIBLE (-3350 4850);
FORCEPROP 1 LAST HDL_TAP TRUE
J 0
(-3025 4775);
DISPLAY 1.234043 (-3025 4775);
PAINT GREEN (-3025 4775);
DISPLAY INVISIBLE (-3025 4775);
FORCEPROP 1 LAST PATH I113
J 0
(-3350 4900);
DISPLAY 0.936170 (-3350 4900);
PAINT GREEN (-3350 4900);
DISPLAY INVISIBLE (-3350 4900);
FORCEADD TAP..6
(-3350 4800);
FORCEPROP 3 LASTPIN (-3300 4800) SIG_NAME M_H_MA<15>
J 0
(-3290 4810);
DISPLAY 0.659574 (-3290 4810);
PAINT MONO (-3290 4810);
DISPLAY INVISIBLE (-3290 4810);
FORCEPROP 1 LASTPIN (-3300 4800) BN 15
J 0
(-3350 4810);
DISPLAY 0.617021 (-3350 4810);
PAINT PINK (-3350 4810);
FORCEPROP 2 LAST CDS_LIB mstr_standard
J 2
(-3350 4800);
DISPLAY 0.787234 (-3350 4800);
PAINT MONO (-3350 4800);
DISPLAY INVISIBLE (-3350 4800);
FORCEPROP 1 LAST BODY_TYPE PLUMBING
J 0
(-3350 4750);
DISPLAY 1.234043 (-3350 4750);
PAINT GREEN (-3350 4750);
DISPLAY INVISIBLE (-3350 4750);
FORCEPROP 1 LAST HDL_TAP TRUE
J 0
(-3025 4675);
DISPLAY 1.234043 (-3025 4675);
PAINT GREEN (-3025 4675);
DISPLAY INVISIBLE (-3025 4675);
FORCEPROP 1 LAST PATH I114
J 0
(-3350 4800);
DISPLAY 0.936170 (-3350 4800);
PAINT GREEN (-3350 4800);
DISPLAY INVISIBLE (-3350 4800);
FORCEADD TAP..6
(-3350 4750);
FORCEPROP 3 LASTPIN (-3300 4750) SIG_NAME M_H_MA<14>
J 0
(-3290 4760);
DISPLAY 0.659574 (-3290 4760);
PAINT MONO (-3290 4760);
DISPLAY INVISIBLE (-3290 4760);
FORCEPROP 1 LASTPIN (-3300 4750) BN 14
J 0
(-3350 4760);
DISPLAY 0.617021 (-3350 4760);
PAINT PINK (-3350 4760);
FORCEPROP 2 LAST CDS_LIB mstr_standard
J 2
(-3350 4750);
DISPLAY 0.787234 (-3350 4750);
PAINT MONO (-3350 4750);
DISPLAY INVISIBLE (-3350 4750);
FORCEPROP 1 LAST BODY_TYPE PLUMBING
J 0
(-3350 4700);
DISPLAY 1.234043 (-3350 4700);
PAINT GREEN (-3350 4700);
DISPLAY INVISIBLE (-3350 4700);
FORCEPROP 1 LAST HDL_TAP TRUE
J 0
(-3025 4625);
DISPLAY 1.234043 (-3025 4625);
PAINT GREEN (-3025 4625);
DISPLAY INVISIBLE (-3025 4625);
FORCEPROP 1 LAST PATH I115
J 0
(-3350 4750);
DISPLAY 0.936170 (-3350 4750);
PAINT GREEN (-3350 4750);
DISPLAY INVISIBLE (-3350 4750);
FORCEADD TAP..6
(-3350 4700);
FORCEPROP 3 LASTPIN (-3300 4700) SIG_NAME M_H_MA<13>
J 0
(-3290 4710);
DISPLAY 0.659574 (-3290 4710);
PAINT MONO (-3290 4710);
DISPLAY INVISIBLE (-3290 4710);
FORCEPROP 1 LASTPIN (-3300 4700) BN 13
J 0
(-3350 4710);
DISPLAY 0.617021 (-3350 4710);
PAINT PINK (-3350 4710);
FORCEPROP 2 LAST CDS_LIB mstr_standard
J 2
(-3350 4700);
DISPLAY 0.787234 (-3350 4700);
PAINT MONO (-3350 4700);
DISPLAY INVISIBLE (-3350 4700);
FORCEPROP 1 LAST BODY_TYPE PLUMBING
J 0
(-3350 4650);
DISPLAY 1.234043 (-3350 4650);
PAINT GREEN (-3350 4650);
DISPLAY INVISIBLE (-3350 4650);
FORCEPROP 1 LAST HDL_TAP TRUE
J 0
(-3025 4575);
DISPLAY 1.234043 (-3025 4575);
PAINT GREEN (-3025 4575);
DISPLAY INVISIBLE (-3025 4575);
FORCEPROP 1 LAST PATH I116
J 0
(-3350 4700);
DISPLAY 0.936170 (-3350 4700);
PAINT GREEN (-3350 4700);
DISPLAY INVISIBLE (-3350 4700);
FORCEADD TAP..6
(-3350 4600);
FORCEPROP 3 LASTPIN (-3300 4600) SIG_NAME M_H_MA<11>
J 0
(-3290 4610);
DISPLAY 0.659574 (-3290 4610);
PAINT MONO (-3290 4610);
DISPLAY INVISIBLE (-3290 4610);
FORCEPROP 1 LASTPIN (-3300 4600) BN 11
J 0
(-3350 4610);
DISPLAY 0.617021 (-3350 4610);
PAINT PINK (-3350 4610);
FORCEPROP 2 LAST CDS_LIB mstr_standard
J 2
(-3350 4600);
DISPLAY 0.787234 (-3350 4600);
PAINT MONO (-3350 4600);
DISPLAY INVISIBLE (-3350 4600);
FORCEPROP 1 LAST BODY_TYPE PLUMBING
J 0
(-3350 4550);
DISPLAY 1.234043 (-3350 4550);
PAINT GREEN (-3350 4550);
DISPLAY INVISIBLE (-3350 4550);
FORCEPROP 1 LAST HDL_TAP TRUE
J 0
(-3025 4475);
DISPLAY 1.234043 (-3025 4475);
PAINT GREEN (-3025 4475);
DISPLAY INVISIBLE (-3025 4475);
FORCEPROP 1 LAST PATH I117
J 0
(-3350 4600);
DISPLAY 0.936170 (-3350 4600);
PAINT GREEN (-3350 4600);
DISPLAY INVISIBLE (-3350 4600);
FORCEADD TAP..6
(-3350 4650);
FORCEPROP 3 LASTPIN (-3300 4650) SIG_NAME M_H_MA<12>
J 0
(-3290 4660);
DISPLAY 0.659574 (-3290 4660);
PAINT MONO (-3290 4660);
DISPLAY INVISIBLE (-3290 4660);
FORCEPROP 1 LASTPIN (-3300 4650) BN 12
J 0
(-3350 4660);
DISPLAY 0.617021 (-3350 4660);
PAINT PINK (-3350 4660);
FORCEPROP 2 LAST CDS_LIB mstr_standard
J 2
(-3350 4650);
DISPLAY 0.787234 (-3350 4650);
PAINT MONO (-3350 4650);
DISPLAY INVISIBLE (-3350 4650);
FORCEPROP 1 LAST BODY_TYPE PLUMBING
J 0
(-3350 4600);
DISPLAY 1.234043 (-3350 4600);
PAINT GREEN (-3350 4600);
DISPLAY INVISIBLE (-3350 4600);
FORCEPROP 1 LAST HDL_TAP TRUE
J 0
(-3025 4525);
DISPLAY 1.234043 (-3025 4525);
PAINT GREEN (-3025 4525);
DISPLAY INVISIBLE (-3025 4525);
FORCEPROP 1 LAST PATH I118
J 0
(-3350 4650);
DISPLAY 0.936170 (-3350 4650);
PAINT GREEN (-3350 4650);
DISPLAY INVISIBLE (-3350 4650);
FORCEADD TAP..6
(-3350 4550);
FORCEPROP 3 LASTPIN (-3300 4550) SIG_NAME M_H_MA<10>
J 0
(-3290 4560);
DISPLAY 0.659574 (-3290 4560);
PAINT MONO (-3290 4560);
DISPLAY INVISIBLE (-3290 4560);
FORCEPROP 1 LASTPIN (-3300 4550) BN 10
J 0
(-3350 4560);
DISPLAY 0.617021 (-3350 4560);
PAINT PINK (-3350 4560);
FORCEPROP 2 LAST CDS_LIB mstr_standard
J 2
(-3350 4550);
DISPLAY 0.787234 (-3350 4550);
PAINT MONO (-3350 4550);
DISPLAY INVISIBLE (-3350 4550);
FORCEPROP 1 LAST BODY_TYPE PLUMBING
J 0
(-3350 4500);
DISPLAY 1.234043 (-3350 4500);
PAINT GREEN (-3350 4500);
DISPLAY INVISIBLE (-3350 4500);
FORCEPROP 1 LAST HDL_TAP TRUE
J 0
(-3025 4425);
DISPLAY 1.234043 (-3025 4425);
PAINT GREEN (-3025 4425);
DISPLAY INVISIBLE (-3025 4425);
FORCEPROP 1 LAST PATH I119
J 0
(-3350 4550);
DISPLAY 0.936170 (-3350 4550);
PAINT GREEN (-3350 4550);
DISPLAY INVISIBLE (-3350 4550);
FORCEADD TAP..6
R 2
(650 4750);
FORCEPROP 3 LASTPIN (600 4750) SIG_NAME M_H_DQS_DP<13>
J 0
(610 4760);
DISPLAY 0.659574 (610 4760);
PAINT MONO (610 4760);
DISPLAY INVISIBLE (610 4760);
FORCEPROP 1 LASTPIN (600 4750) BN 13
J 2
(650 4760);
DISPLAY 0.617021 (650 4760);
PAINT PINK (650 4760);
FORCEPROP 2 LAST CDS_LIB mstr_standard
J 0
(650 4750);
DISPLAY 0.787234 (650 4750);
PAINT MONO (650 4750);
DISPLAY INVISIBLE (650 4750);
FORCEPROP 1 LAST BODY_TYPE PLUMBING
J 2
(650 4700);
DISPLAY 1.234043 (650 4700);
PAINT GREEN (650 4700);
DISPLAY INVISIBLE (650 4700);
FORCEPROP 1 LAST HDL_TAP TRUE
J 2
(325 4625);
DISPLAY 1.234043 (325 4625);
PAINT GREEN (325 4625);
DISPLAY INVISIBLE (325 4625);
FORCEPROP 1 LAST PATH I12
J 2
(650 4750);
DISPLAY 0.936170 (650 4750);
PAINT GREEN (650 4750);
DISPLAY INVISIBLE (650 4750);
FORCEADD TAP..6
(-3350 4500);
FORCEPROP 3 LASTPIN (-3300 4500) SIG_NAME M_H_MA<9>
J 0
(-3290 4510);
DISPLAY 0.659574 (-3290 4510);
PAINT MONO (-3290 4510);
DISPLAY INVISIBLE (-3290 4510);
FORCEPROP 1 LASTPIN (-3300 4500) BN 9
J 0
(-3350 4510);
DISPLAY 0.617021 (-3350 4510);
PAINT PINK (-3350 4510);
FORCEPROP 2 LAST CDS_LIB mstr_standard
J 2
(-3350 4500);
DISPLAY 0.787234 (-3350 4500);
PAINT MONO (-3350 4500);
DISPLAY INVISIBLE (-3350 4500);
FORCEPROP 1 LAST BODY_TYPE PLUMBING
J 0
(-3350 4450);
DISPLAY 1.234043 (-3350 4450);
PAINT GREEN (-3350 4450);
DISPLAY INVISIBLE (-3350 4450);
FORCEPROP 1 LAST HDL_TAP TRUE
J 0
(-3025 4375);
DISPLAY 1.234043 (-3025 4375);
PAINT GREEN (-3025 4375);
DISPLAY INVISIBLE (-3025 4375);
FORCEPROP 1 LAST PATH I120
J 0
(-3350 4500);
DISPLAY 0.936170 (-3350 4500);
PAINT GREEN (-3350 4500);
DISPLAY INVISIBLE (-3350 4500);
FORCEADD TAP..6
(-3350 4450);
FORCEPROP 3 LASTPIN (-3300 4450) SIG_NAME M_H_MA<8>
J 0
(-3290 4460);
DISPLAY 0.659574 (-3290 4460);
PAINT MONO (-3290 4460);
DISPLAY INVISIBLE (-3290 4460);
FORCEPROP 1 LASTPIN (-3300 4450) BN 8
J 0
(-3350 4460);
DISPLAY 0.617021 (-3350 4460);
PAINT PINK (-3350 4460);
FORCEPROP 2 LAST CDS_LIB mstr_standard
J 2
(-3350 4450);
DISPLAY 0.787234 (-3350 4450);
PAINT MONO (-3350 4450);
DISPLAY INVISIBLE (-3350 4450);
FORCEPROP 1 LAST BODY_TYPE PLUMBING
J 0
(-3350 4400);
DISPLAY 1.234043 (-3350 4400);
PAINT GREEN (-3350 4400);
DISPLAY INVISIBLE (-3350 4400);
FORCEPROP 1 LAST HDL_TAP TRUE
J 0
(-3025 4325);
DISPLAY 1.234043 (-3025 4325);
PAINT GREEN (-3025 4325);
DISPLAY INVISIBLE (-3025 4325);
FORCEPROP 1 LAST PATH I121
J 0
(-3350 4450);
DISPLAY 0.936170 (-3350 4450);
PAINT GREEN (-3350 4450);
DISPLAY INVISIBLE (-3350 4450);
FORCEADD TAP..6
(-3350 4350);
FORCEPROP 3 LASTPIN (-3300 4350) SIG_NAME M_H_MA<6>
J 0
(-3290 4360);
DISPLAY 0.659574 (-3290 4360);
PAINT MONO (-3290 4360);
DISPLAY INVISIBLE (-3290 4360);
FORCEPROP 1 LASTPIN (-3300 4350) BN 6
J 0
(-3350 4360);
DISPLAY 0.617021 (-3350 4360);
PAINT PINK (-3350 4360);
FORCEPROP 2 LAST CDS_LIB mstr_standard
J 2
(-3350 4350);
DISPLAY 0.787234 (-3350 4350);
PAINT MONO (-3350 4350);
DISPLAY INVISIBLE (-3350 4350);
FORCEPROP 1 LAST BODY_TYPE PLUMBING
J 0
(-3350 4300);
DISPLAY 1.234043 (-3350 4300);
PAINT GREEN (-3350 4300);
DISPLAY INVISIBLE (-3350 4300);
FORCEPROP 1 LAST HDL_TAP TRUE
J 0
(-3025 4225);
DISPLAY 1.234043 (-3025 4225);
PAINT GREEN (-3025 4225);
DISPLAY INVISIBLE (-3025 4225);
FORCEPROP 1 LAST PATH I122
J 0
(-3350 4350);
DISPLAY 0.936170 (-3350 4350);
PAINT GREEN (-3350 4350);
DISPLAY INVISIBLE (-3350 4350);
FORCEADD TAP..6
(-3350 4400);
FORCEPROP 3 LASTPIN (-3300 4400) SIG_NAME M_H_MA<7>
J 0
(-3290 4410);
DISPLAY 0.659574 (-3290 4410);
PAINT MONO (-3290 4410);
DISPLAY INVISIBLE (-3290 4410);
FORCEPROP 1 LASTPIN (-3300 4400) BN 7
J 0
(-3350 4410);
DISPLAY 0.617021 (-3350 4410);
PAINT PINK (-3350 4410);
FORCEPROP 2 LAST CDS_LIB mstr_standard
J 2
(-3350 4400);
DISPLAY 0.787234 (-3350 4400);
PAINT MONO (-3350 4400);
DISPLAY INVISIBLE (-3350 4400);
FORCEPROP 1 LAST BODY_TYPE PLUMBING
J 0
(-3350 4350);
DISPLAY 1.234043 (-3350 4350);
PAINT GREEN (-3350 4350);
DISPLAY INVISIBLE (-3350 4350);
FORCEPROP 1 LAST HDL_TAP TRUE
J 0
(-3025 4275);
DISPLAY 1.234043 (-3025 4275);
PAINT GREEN (-3025 4275);
DISPLAY INVISIBLE (-3025 4275);
FORCEPROP 1 LAST PATH I123
J 0
(-3350 4400);
DISPLAY 0.936170 (-3350 4400);
PAINT GREEN (-3350 4400);
DISPLAY INVISIBLE (-3350 4400);
FORCEADD TAP..6
(-3350 4300);
FORCEPROP 3 LASTPIN (-3300 4300) SIG_NAME M_H_MA<5>
J 0
(-3290 4310);
DISPLAY 0.659574 (-3290 4310);
PAINT MONO (-3290 4310);
DISPLAY INVISIBLE (-3290 4310);
FORCEPROP 1 LASTPIN (-3300 4300) BN 5
J 0
(-3350 4310);
DISPLAY 0.617021 (-3350 4310);
PAINT PINK (-3350 4310);
FORCEPROP 2 LAST CDS_LIB mstr_standard
J 2
(-3350 4300);
DISPLAY 0.787234 (-3350 4300);
PAINT MONO (-3350 4300);
DISPLAY INVISIBLE (-3350 4300);
FORCEPROP 1 LAST BODY_TYPE PLUMBING
J 0
(-3350 4250);
DISPLAY 1.234043 (-3350 4250);
PAINT GREEN (-3350 4250);
DISPLAY INVISIBLE (-3350 4250);
FORCEPROP 1 LAST HDL_TAP TRUE
J 0
(-3025 4175);
DISPLAY 1.234043 (-3025 4175);
PAINT GREEN (-3025 4175);
DISPLAY INVISIBLE (-3025 4175);
FORCEPROP 1 LAST PATH I124
J 0
(-3350 4300);
DISPLAY 0.936170 (-3350 4300);
PAINT GREEN (-3350 4300);
DISPLAY INVISIBLE (-3350 4300);
FORCEADD TAP..6
(-3350 4200);
FORCEPROP 3 LASTPIN (-3300 4200) SIG_NAME M_H_MA<3>
J 0
(-3290 4210);
DISPLAY 0.659574 (-3290 4210);
PAINT MONO (-3290 4210);
DISPLAY INVISIBLE (-3290 4210);
FORCEPROP 1 LASTPIN (-3300 4200) BN 3
J 0
(-3350 4210);
DISPLAY 0.617021 (-3350 4210);
PAINT PINK (-3350 4210);
FORCEPROP 2 LAST CDS_LIB mstr_standard
J 2
(-3350 4200);
DISPLAY 0.787234 (-3350 4200);
PAINT MONO (-3350 4200);
DISPLAY INVISIBLE (-3350 4200);
FORCEPROP 1 LAST BODY_TYPE PLUMBING
J 0
(-3350 4150);
DISPLAY 1.234043 (-3350 4150);
PAINT GREEN (-3350 4150);
DISPLAY INVISIBLE (-3350 4150);
FORCEPROP 1 LAST HDL_TAP TRUE
J 0
(-3025 4075);
DISPLAY 1.234043 (-3025 4075);
PAINT GREEN (-3025 4075);
DISPLAY INVISIBLE (-3025 4075);
FORCEPROP 1 LAST PATH I125
J 0
(-3350 4200);
DISPLAY 0.936170 (-3350 4200);
PAINT GREEN (-3350 4200);
DISPLAY INVISIBLE (-3350 4200);
FORCEADD TAP..6
(-3350 4250);
FORCEPROP 3 LASTPIN (-3300 4250) SIG_NAME M_H_MA<4>
J 0
(-3290 4260);
DISPLAY 0.659574 (-3290 4260);
PAINT MONO (-3290 4260);
DISPLAY INVISIBLE (-3290 4260);
FORCEPROP 1 LASTPIN (-3300 4250) BN 4
J 0
(-3350 4260);
DISPLAY 0.617021 (-3350 4260);
PAINT PINK (-3350 4260);
FORCEPROP 2 LAST CDS_LIB mstr_standard
J 2
(-3350 4250);
DISPLAY 0.787234 (-3350 4250);
PAINT MONO (-3350 4250);
DISPLAY INVISIBLE (-3350 4250);
FORCEPROP 1 LAST BODY_TYPE PLUMBING
J 0
(-3350 4200);
DISPLAY 1.234043 (-3350 4200);
PAINT GREEN (-3350 4200);
DISPLAY INVISIBLE (-3350 4200);
FORCEPROP 1 LAST HDL_TAP TRUE
J 0
(-3025 4125);
DISPLAY 1.234043 (-3025 4125);
PAINT GREEN (-3025 4125);
DISPLAY INVISIBLE (-3025 4125);
FORCEPROP 1 LAST PATH I126
J 0
(-3350 4250);
DISPLAY 0.936170 (-3350 4250);
PAINT GREEN (-3350 4250);
DISPLAY INVISIBLE (-3350 4250);
FORCEADD TAP..6
(-3350 4150);
FORCEPROP 3 LASTPIN (-3300 4150) SIG_NAME M_H_MA<2>
J 0
(-3290 4160);
DISPLAY 0.659574 (-3290 4160);
PAINT MONO (-3290 4160);
DISPLAY INVISIBLE (-3290 4160);
FORCEPROP 1 LASTPIN (-3300 4150) BN 2
J 0
(-3350 4160);
DISPLAY 0.617021 (-3350 4160);
PAINT PINK (-3350 4160);
FORCEPROP 2 LAST CDS_LIB mstr_standard
J 2
(-3350 4150);
DISPLAY 0.787234 (-3350 4150);
PAINT MONO (-3350 4150);
DISPLAY INVISIBLE (-3350 4150);
FORCEPROP 1 LAST BODY_TYPE PLUMBING
J 0
(-3350 4100);
DISPLAY 1.234043 (-3350 4100);
PAINT GREEN (-3350 4100);
DISPLAY INVISIBLE (-3350 4100);
FORCEPROP 1 LAST HDL_TAP TRUE
J 0
(-3025 4025);
DISPLAY 1.234043 (-3025 4025);
PAINT GREEN (-3025 4025);
DISPLAY INVISIBLE (-3025 4025);
FORCEPROP 1 LAST PATH I127
J 0
(-3350 4150);
DISPLAY 0.936170 (-3350 4150);
PAINT GREEN (-3350 4150);
DISPLAY INVISIBLE (-3350 4150);
FORCEADD TAP..6
(-3350 4050);
FORCEPROP 3 LASTPIN (-3300 4050) SIG_NAME M_H_MA<0>
J 0
(-3290 4060);
DISPLAY 0.659574 (-3290 4060);
PAINT MONO (-3290 4060);
DISPLAY INVISIBLE (-3290 4060);
FORCEPROP 1 LASTPIN (-3300 4050) BN 0
J 0
(-3350 4060);
DISPLAY 0.617021 (-3350 4060);
PAINT PINK (-3350 4060);
FORCEPROP 2 LAST CDS_LIB mstr_standard
J 2
(-3350 4050);
DISPLAY 0.787234 (-3350 4050);
PAINT MONO (-3350 4050);
DISPLAY INVISIBLE (-3350 4050);
FORCEPROP 1 LAST BODY_TYPE PLUMBING
J 0
(-3350 4000);
DISPLAY 1.234043 (-3350 4000);
PAINT GREEN (-3350 4000);
DISPLAY INVISIBLE (-3350 4000);
FORCEPROP 1 LAST HDL_TAP TRUE
J 0
(-3025 3925);
DISPLAY 1.234043 (-3025 3925);
PAINT GREEN (-3025 3925);
DISPLAY INVISIBLE (-3025 3925);
FORCEPROP 1 LAST PATH I128
J 0
(-3350 4050);
DISPLAY 0.936170 (-3350 4050);
PAINT GREEN (-3350 4050);
DISPLAY INVISIBLE (-3350 4050);
FORCEADD TAP..6
(-3350 4100);
FORCEPROP 3 LASTPIN (-3300 4100) SIG_NAME M_H_MA<1>
J 0
(-3290 4110);
DISPLAY 0.659574 (-3290 4110);
PAINT MONO (-3290 4110);
DISPLAY INVISIBLE (-3290 4110);
FORCEPROP 1 LASTPIN (-3300 4100) BN 1
J 0
(-3350 4110);
DISPLAY 0.617021 (-3350 4110);
PAINT PINK (-3350 4110);
FORCEPROP 2 LAST CDS_LIB mstr_standard
J 2
(-3350 4100);
DISPLAY 0.787234 (-3350 4100);
PAINT MONO (-3350 4100);
DISPLAY INVISIBLE (-3350 4100);
FORCEPROP 1 LAST BODY_TYPE PLUMBING
J 0
(-3350 4050);
DISPLAY 1.234043 (-3350 4050);
PAINT GREEN (-3350 4050);
DISPLAY INVISIBLE (-3350 4050);
FORCEPROP 1 LAST HDL_TAP TRUE
J 0
(-3025 3975);
DISPLAY 1.234043 (-3025 3975);
PAINT GREEN (-3025 3975);
DISPLAY INVISIBLE (-3025 3975);
FORCEPROP 1 LAST PATH I129
J 0
(-3350 4100);
DISPLAY 0.936170 (-3350 4100);
PAINT GREEN (-3350 4100);
DISPLAY INVISIBLE (-3350 4100);
FORCEADD TAP..6
R 2
(650 4650);
FORCEPROP 3 LASTPIN (600 4650) SIG_NAME M_H_DQS_DP<12>
J 0
(610 4660);
DISPLAY 0.659574 (610 4660);
PAINT MONO (610 4660);
DISPLAY INVISIBLE (610 4660);
FORCEPROP 1 LASTPIN (600 4650) BN 12
J 2
(650 4660);
DISPLAY 0.617021 (650 4660);
PAINT PINK (650 4660);
FORCEPROP 2 LAST CDS_LIB mstr_standard
J 0
(650 4650);
DISPLAY 0.787234 (650 4650);
PAINT MONO (650 4650);
DISPLAY INVISIBLE (650 4650);
FORCEPROP 1 LAST BODY_TYPE PLUMBING
J 2
(650 4600);
DISPLAY 1.234043 (650 4600);
PAINT GREEN (650 4600);
DISPLAY INVISIBLE (650 4600);
FORCEPROP 1 LAST HDL_TAP TRUE
J 2
(325 4525);
DISPLAY 1.234043 (325 4525);
PAINT GREEN (325 4525);
DISPLAY INVISIBLE (325 4525);
FORCEPROP 1 LAST PATH I13
J 2
(650 4650);
DISPLAY 0.936170 (650 4650);
PAINT GREEN (650 4650);
DISPLAY INVISIBLE (650 4650);
FORCEADD OFFPAGE..1
(-4000 4950);
FORCEPROP 2 LAST $XR1 80 
J 0
(-4341 4950);
DISPLAY 0.638298 (-4341 4950);
PAINT MONO (-4341 4950);
FORCEPROP 2 LAST $XR0 58 
J 0
(-4251 4950);
DISPLAY 0.638298 (-4251 4950);
PAINT MONO (-4251 4950);
FORCEPROP 2 LAST CDS_LIB mstr_standard
J 0
(-4000 4950);
DISPLAY 0.787234 (-4000 4950);
PAINT MONO (-4000 4950);
DISPLAY INVISIBLE (-4000 4950);
FORCEPROP 1 LAST OFFPAGE TRUE
J 0
(-3675 4825);
DISPLAY 0.936170 (-3675 4825);
PAINT GREEN (-3675 4825);
DISPLAY INVISIBLE (-3675 4825);
FORCEPROP 1 LAST COMMENT_BODY TRUE
J 0
(-3875 4850);
DISPLAY 0.936170 (-3875 4850);
PAINT GREEN (-3875 4850);
DISPLAY INVISIBLE (-3875 4850);
FORCEPROP 2 LAST PATH I130
J 0
(-3950 5025);
DISPLAY 0.787234 (-3950 5025);
PAINT MONO (-3950 5025);
DISPLAY INVISIBLE (-3950 5025);
FORCEADD TAP..6
(-3350 3950);
FORCEPROP 3 LASTPIN (-3300 3950) SIG_NAME M_H_BA<1>
J 0
(-3290 3960);
DISPLAY 0.659574 (-3290 3960);
PAINT MONO (-3290 3960);
DISPLAY INVISIBLE (-3290 3960);
FORCEPROP 1 LASTPIN (-3300 3950) BN 1
J 0
(-3350 3960);
DISPLAY 0.617021 (-3350 3960);
PAINT PINK (-3350 3960);
FORCEPROP 2 LAST CDS_LIB mstr_standard
J 0
(-3350 3950);
DISPLAY 0.787234 (-3350 3950);
PAINT MONO (-3350 3950);
DISPLAY INVISIBLE (-3350 3950);
FORCEPROP 1 LAST BODY_TYPE PLUMBING
J 0
(-3350 3900);
DISPLAY 1.234043 (-3350 3900);
PAINT GREEN (-3350 3900);
DISPLAY INVISIBLE (-3350 3900);
FORCEPROP 1 LAST HDL_TAP TRUE
J 0
(-3025 3825);
DISPLAY 1.234043 (-3025 3825);
PAINT GREEN (-3025 3825);
DISPLAY INVISIBLE (-3025 3825);
FORCEPROP 1 LAST PATH I131
J 0
(-3350 3950);
DISPLAY 0.936170 (-3350 3950);
PAINT GREEN (-3350 3950);
DISPLAY INVISIBLE (-3350 3950);
FORCEADD TAP..6
(-3350 3900);
FORCEPROP 3 LASTPIN (-3300 3900) SIG_NAME M_H_BA<0>
J 0
(-3290 3910);
DISPLAY 0.659574 (-3290 3910);
PAINT MONO (-3290 3910);
DISPLAY INVISIBLE (-3290 3910);
FORCEPROP 1 LASTPIN (-3300 3900) BN 0
J 0
(-3350 3910);
DISPLAY 0.617021 (-3350 3910);
PAINT PINK (-3350 3910);
FORCEPROP 2 LAST CDS_LIB mstr_standard
J 0
(-3350 3900);
DISPLAY 0.787234 (-3350 3900);
PAINT MONO (-3350 3900);
DISPLAY INVISIBLE (-3350 3900);
FORCEPROP 1 LAST BODY_TYPE PLUMBING
J 0
(-3350 3850);
DISPLAY 1.234043 (-3350 3850);
PAINT GREEN (-3350 3850);
DISPLAY INVISIBLE (-3350 3850);
FORCEPROP 1 LAST HDL_TAP TRUE
J 0
(-3025 3775);
DISPLAY 1.234043 (-3025 3775);
PAINT GREEN (-3025 3775);
DISPLAY INVISIBLE (-3025 3775);
FORCEPROP 1 LAST PATH I132
J 0
(-3350 3900);
DISPLAY 0.936170 (-3350 3900);
PAINT GREEN (-3350 3900);
DISPLAY INVISIBLE (-3350 3900);
FORCEADD TAP..6
(-3350 3800);
FORCEPROP 3 LASTPIN (-3300 3800) SIG_NAME M_H_BG<0>
J 0
(-3290 3810);
DISPLAY 0.659574 (-3290 3810);
PAINT MONO (-3290 3810);
DISPLAY INVISIBLE (-3290 3810);
FORCEPROP 1 LASTPIN (-3300 3800) BN 0
J 0
(-3350 3810);
DISPLAY 0.617021 (-3350 3810);
PAINT PINK (-3350 3810);
FORCEPROP 2 LAST CDS_LIB mstr_standard
J 0
(-3350 3800);
DISPLAY 0.787234 (-3350 3800);
PAINT MONO (-3350 3800);
DISPLAY INVISIBLE (-3350 3800);
FORCEPROP 1 LAST BODY_TYPE PLUMBING
J 0
(-3350 3750);
DISPLAY 1.234043 (-3350 3750);
PAINT GREEN (-3350 3750);
DISPLAY INVISIBLE (-3350 3750);
FORCEPROP 1 LAST HDL_TAP TRUE
J 0
(-3025 3675);
DISPLAY 1.234043 (-3025 3675);
PAINT GREEN (-3025 3675);
DISPLAY INVISIBLE (-3025 3675);
FORCEPROP 1 LAST PATH I133
J 0
(-3350 3800);
DISPLAY 0.936170 (-3350 3800);
PAINT GREEN (-3350 3800);
DISPLAY INVISIBLE (-3350 3800);
FORCEADD TAP..6
(-3350 3850);
FORCEPROP 3 LASTPIN (-3300 3850) SIG_NAME M_H_BG<1>
J 0
(-3290 3860);
DISPLAY 0.659574 (-3290 3860);
PAINT MONO (-3290 3860);
DISPLAY INVISIBLE (-3290 3860);
FORCEPROP 1 LASTPIN (-3300 3850) BN 1
J 0
(-3350 3860);
DISPLAY 0.617021 (-3350 3860);
PAINT PINK (-3350 3860);
FORCEPROP 2 LAST CDS_LIB mstr_standard
J 0
(-3350 3850);
DISPLAY 0.787234 (-3350 3850);
PAINT MONO (-3350 3850);
DISPLAY INVISIBLE (-3350 3850);
FORCEPROP 1 LAST BODY_TYPE PLUMBING
J 0
(-3350 3800);
DISPLAY 1.234043 (-3350 3800);
PAINT GREEN (-3350 3800);
DISPLAY INVISIBLE (-3350 3800);
FORCEPROP 1 LAST HDL_TAP TRUE
J 0
(-3025 3725);
DISPLAY 1.234043 (-3025 3725);
PAINT GREEN (-3025 3725);
DISPLAY INVISIBLE (-3025 3725);
FORCEPROP 1 LAST PATH I134
J 0
(-3350 3850);
DISPLAY 0.936170 (-3350 3850);
PAINT GREEN (-3350 3850);
DISPLAY INVISIBLE (-3350 3850);
FORCEADD OFFPAGE..1
(-4000 3500);
FORCEPROP 2 LAST $XR1 80 
J 0
(-4341 3500);
DISPLAY 0.638298 (-4341 3500);
PAINT MONO (-4341 3500);
FORCEPROP 2 LAST $XR0 58 
J 0
(-4251 3500);
DISPLAY 0.638298 (-4251 3500);
PAINT MONO (-4251 3500);
FORCEPROP 2 LAST CDS_LIB mstr_standard
J 0
(-4000 3500);
DISPLAY 0.787234 (-4000 3500);
PAINT MONO (-4000 3500);
DISPLAY INVISIBLE (-4000 3500);
FORCEPROP 1 LAST OFFPAGE TRUE
J 0
(-3675 3375);
DISPLAY 0.936170 (-3675 3375);
PAINT GREEN (-3675 3375);
DISPLAY INVISIBLE (-3675 3375);
FORCEPROP 1 LAST COMMENT_BODY TRUE
J 0
(-3875 3400);
DISPLAY 0.936170 (-3875 3400);
PAINT GREEN (-3875 3400);
DISPLAY INVISIBLE (-3875 3400);
FORCEPROP 2 LAST PATH I135
J 0
(-3950 3575);
DISPLAY 0.787234 (-3950 3575);
PAINT MONO (-3950 3575);
DISPLAY INVISIBLE (-3950 3575);
FORCEADD OFFPAGE..1
(-4000 4000);
FORCEPROP 2 LAST $XR1 80 
J 0
(-4341 4000);
DISPLAY 0.638298 (-4341 4000);
PAINT MONO (-4341 4000);
FORCEPROP 2 LAST $XR0 58 
J 0
(-4251 4000);
DISPLAY 0.638298 (-4251 4000);
PAINT MONO (-4251 4000);
FORCEPROP 2 LAST CDS_LIB mstr_standard
J 0
(-4000 4000);
DISPLAY 0.787234 (-4000 4000);
PAINT MONO (-4000 4000);
DISPLAY INVISIBLE (-4000 4000);
FORCEPROP 1 LAST OFFPAGE TRUE
J 0
(-3675 3875);
DISPLAY 0.936170 (-3675 3875);
PAINT GREEN (-3675 3875);
DISPLAY INVISIBLE (-3675 3875);
FORCEPROP 1 LAST COMMENT_BODY TRUE
J 0
(-3875 3900);
DISPLAY 0.936170 (-3875 3900);
PAINT GREEN (-3875 3900);
DISPLAY INVISIBLE (-3875 3900);
FORCEPROP 2 LAST PATH I136
J 0
(-3950 4075);
DISPLAY 0.787234 (-3950 4075);
PAINT MONO (-3950 4075);
DISPLAY INVISIBLE (-3950 4075);
FORCEADD OFFPAGE..1
(-4000 3900);
FORCEPROP 2 LAST $XR1 80 
J 0
(-4341 3900);
DISPLAY 0.638298 (-4341 3900);
PAINT MONO (-4341 3900);
FORCEPROP 2 LAST $XR0 58 
J 0
(-4251 3900);
DISPLAY 0.638298 (-4251 3900);
PAINT MONO (-4251 3900);
FORCEPROP 2 LAST CDS_LIB mstr_standard
J 0
(-4000 3900);
DISPLAY 0.787234 (-4000 3900);
PAINT MONO (-4000 3900);
DISPLAY INVISIBLE (-4000 3900);
FORCEPROP 1 LAST OFFPAGE TRUE
J 0
(-3675 3775);
DISPLAY 0.936170 (-3675 3775);
PAINT GREEN (-3675 3775);
DISPLAY INVISIBLE (-3675 3775);
FORCEPROP 1 LAST COMMENT_BODY TRUE
J 0
(-3875 3800);
DISPLAY 0.936170 (-3875 3800);
PAINT GREEN (-3875 3800);
DISPLAY INVISIBLE (-3875 3800);
FORCEPROP 2 LAST PATH I137
J 0
(-3950 3975);
DISPLAY 0.787234 (-3950 3975);
PAINT MONO (-3950 3975);
DISPLAY INVISIBLE (-3950 3975);
FORCEADD TAP..6
(-3350 2800);
FORCEPROP 3 LASTPIN (-3300 2800) SIG_NAME M_H_ECC<7>
J 0
(-3290 2810);
DISPLAY 0.659574 (-3290 2810);
PAINT MONO (-3290 2810);
DISPLAY INVISIBLE (-3290 2810);
FORCEPROP 1 LASTPIN (-3300 2800) BN 7
J 0
(-3350 2810);
DISPLAY 0.617021 (-3350 2810);
PAINT PINK (-3350 2810);
FORCEPROP 2 LAST CDS_LIB mstr_standard
J 0
(-3350 2800);
DISPLAY 0.787234 (-3350 2800);
PAINT MONO (-3350 2800);
DISPLAY INVISIBLE (-3350 2800);
FORCEPROP 1 LAST BODY_TYPE PLUMBING
J 0
(-3350 2750);
DISPLAY 1.234043 (-3350 2750);
PAINT GREEN (-3350 2750);
DISPLAY INVISIBLE (-3350 2750);
FORCEPROP 1 LAST HDL_TAP TRUE
J 0
(-3025 2675);
DISPLAY 1.234043 (-3025 2675);
PAINT GREEN (-3025 2675);
DISPLAY INVISIBLE (-3025 2675);
FORCEPROP 1 LAST PATH I138
J 0
(-3350 2800);
DISPLAY 0.936170 (-3350 2800);
PAINT GREEN (-3350 2800);
DISPLAY INVISIBLE (-3350 2800);
FORCEADD TAP..6
(-3350 2850);
FORCEPROP 3 LASTPIN (-3300 2850) SIG_NAME M_H_ECC<6>
J 0
(-3290 2860);
DISPLAY 0.659574 (-3290 2860);
PAINT MONO (-3290 2860);
DISPLAY INVISIBLE (-3290 2860);
FORCEPROP 1 LASTPIN (-3300 2850) BN 6
J 0
(-3350 2860);
DISPLAY 0.617021 (-3350 2860);
PAINT PINK (-3350 2860);
FORCEPROP 2 LAST CDS_LIB mstr_standard
J 0
(-3350 2850);
DISPLAY 0.787234 (-3350 2850);
PAINT MONO (-3350 2850);
DISPLAY INVISIBLE (-3350 2850);
FORCEPROP 1 LAST BODY_TYPE PLUMBING
J 0
(-3350 2800);
DISPLAY 1.234043 (-3350 2800);
PAINT GREEN (-3350 2800);
DISPLAY INVISIBLE (-3350 2800);
FORCEPROP 1 LAST HDL_TAP TRUE
J 0
(-3025 2725);
DISPLAY 1.234043 (-3025 2725);
PAINT GREEN (-3025 2725);
DISPLAY INVISIBLE (-3025 2725);
FORCEPROP 1 LAST PATH I139
J 0
(-3350 2850);
DISPLAY 0.936170 (-3350 2850);
PAINT GREEN (-3350 2850);
DISPLAY INVISIBLE (-3350 2850);
FORCEADD PVDDQ_GHJ..1
(-1525 2525);
FORCEPROP 3 LASTPIN (-1525 2475) SIG_NAME PVDDQ_GHJ\g
J 0
(-1515 2485);
DISPLAY 0.659574 (-1515 2485);
PAINT MONO (-1515 2485);
DISPLAY INVISIBLE (-1515 2485);
FORCEPROP 1 LAST VOLTAGE 1.2V
J 0
(-1570 2482);
DISPLAY 0.340426 (-1570 2482);
PAINT SKYBLUE (-1570 2482);
DISPLAY INVISIBLE (-1570 2482);
FORCEPROP 2 LAST BOM_COST MEM
J 0
(-1525 2530);
PAINT ORANGE (-1525 2530);
DISPLAY INVISIBLE (-1525 2530);
FORCEPROP 2 LAST CDS_LIB mstr_symbols
J 0
(-1525 2525);
PAINT ORANGE (-1525 2525);
DISPLAY INVISIBLE (-1525 2525);
FORCEPROP 1 LAST BODY_TYPE PLUMBING
J 0
(-1570 2482);
DISPLAY 0.340426 (-1570 2482);
PAINT GREEN (-1570 2482);
DISPLAY INVISIBLE (-1570 2482);
FORCEPROP 1 LAST PATH I14
J 0
(-1475 2550);
DISPLAY 0.872340 (-1475 2550);
PAINT AQUA (-1475 2550);
DISPLAY INVISIBLE (-1475 2550);
FORCEPROP 2 LAST ROOM DDR4_CH_H
J 0
(-1525 2625);
DISPLAY 0.787234 (-1525 2625);
PAINT ORANGE (-1525 2625);
DISPLAY INVISIBLE (-1525 2625);
FORCEPROP 1 LAST HDL_POWER PVDDQ_GHJ
J 1
(-1525 2575);
DISPLAY 0.872340 (-1525 2575);
PAINT GREEN (-1525 2575);
DISPLAY INVISIBLE (-1525 2575);
FORCEADD TAP..6
(-3350 2750);
FORCEPROP 3 LASTPIN (-3300 2750) SIG_NAME M_H_ECC<4>
J 0
(-3290 2760);
DISPLAY 0.659574 (-3290 2760);
PAINT MONO (-3290 2760);
DISPLAY INVISIBLE (-3290 2760);
FORCEPROP 1 LASTPIN (-3300 2750) BN 4
J 0
(-3350 2760);
DISPLAY 0.617021 (-3350 2760);
PAINT PINK (-3350 2760);
FORCEPROP 2 LAST CDS_LIB mstr_standard
J 0
(-3350 2750);
DISPLAY 0.787234 (-3350 2750);
PAINT MONO (-3350 2750);
DISPLAY INVISIBLE (-3350 2750);
FORCEPROP 1 LAST BODY_TYPE PLUMBING
J 0
(-3350 2700);
DISPLAY 1.234043 (-3350 2700);
PAINT GREEN (-3350 2700);
DISPLAY INVISIBLE (-3350 2700);
FORCEPROP 1 LAST HDL_TAP TRUE
J 0
(-3025 2625);
DISPLAY 1.234043 (-3025 2625);
PAINT GREEN (-3025 2625);
DISPLAY INVISIBLE (-3025 2625);
FORCEPROP 1 LAST PATH I140
J 0
(-3350 2750);
DISPLAY 0.936170 (-3350 2750);
PAINT GREEN (-3350 2750);
DISPLAY INVISIBLE (-3350 2750);
FORCEADD TAP..6
(-3350 2700);
FORCEPROP 3 LASTPIN (-3300 2700) SIG_NAME M_H_ECC<5>
J 0
(-3290 2710);
DISPLAY 0.659574 (-3290 2710);
PAINT MONO (-3290 2710);
DISPLAY INVISIBLE (-3290 2710);
FORCEPROP 1 LASTPIN (-3300 2700) BN 5
J 0
(-3350 2710);
DISPLAY 0.617021 (-3350 2710);
PAINT PINK (-3350 2710);
FORCEPROP 2 LAST CDS_LIB mstr_standard
J 0
(-3350 2700);
DISPLAY 0.787234 (-3350 2700);
PAINT MONO (-3350 2700);
DISPLAY INVISIBLE (-3350 2700);
FORCEPROP 1 LAST BODY_TYPE PLUMBING
J 0
(-3350 2650);
DISPLAY 1.234043 (-3350 2650);
PAINT GREEN (-3350 2650);
DISPLAY INVISIBLE (-3350 2650);
FORCEPROP 1 LAST HDL_TAP TRUE
J 0
(-3025 2575);
DISPLAY 1.234043 (-3025 2575);
PAINT GREEN (-3025 2575);
DISPLAY INVISIBLE (-3025 2575);
FORCEPROP 1 LAST PATH I141
J 0
(-3350 2700);
DISPLAY 0.936170 (-3350 2700);
PAINT GREEN (-3350 2700);
DISPLAY INVISIBLE (-3350 2700);
FORCEADD TAP..6
(-3350 2650);
FORCEPROP 3 LASTPIN (-3300 2650) SIG_NAME M_H_ECC<2>
J 0
(-3290 2660);
DISPLAY 0.659574 (-3290 2660);
PAINT MONO (-3290 2660);
DISPLAY INVISIBLE (-3290 2660);
FORCEPROP 1 LASTPIN (-3300 2650) BN 2
J 0
(-3350 2660);
DISPLAY 0.617021 (-3350 2660);
PAINT PINK (-3350 2660);
FORCEPROP 2 LAST CDS_LIB mstr_standard
J 0
(-3350 2650);
DISPLAY 0.787234 (-3350 2650);
PAINT MONO (-3350 2650);
DISPLAY INVISIBLE (-3350 2650);
FORCEPROP 1 LAST BODY_TYPE PLUMBING
J 0
(-3350 2600);
DISPLAY 1.234043 (-3350 2600);
PAINT GREEN (-3350 2600);
DISPLAY INVISIBLE (-3350 2600);
FORCEPROP 1 LAST HDL_TAP TRUE
J 0
(-3025 2525);
DISPLAY 1.234043 (-3025 2525);
PAINT GREEN (-3025 2525);
DISPLAY INVISIBLE (-3025 2525);
FORCEPROP 1 LAST PATH I142
J 0
(-3350 2650);
DISPLAY 0.936170 (-3350 2650);
PAINT GREEN (-3350 2650);
DISPLAY INVISIBLE (-3350 2650);
FORCEADD TAP..6
(-3350 2550);
FORCEPROP 3 LASTPIN (-3300 2550) SIG_NAME M_H_ECC<0>
J 0
(-3290 2560);
DISPLAY 0.659574 (-3290 2560);
PAINT MONO (-3290 2560);
DISPLAY INVISIBLE (-3290 2560);
FORCEPROP 1 LASTPIN (-3300 2550) BN 0
J 0
(-3350 2560);
DISPLAY 0.617021 (-3350 2560);
PAINT PINK (-3350 2560);
FORCEPROP 2 LAST CDS_LIB mstr_standard
J 0
(-3350 2550);
DISPLAY 0.787234 (-3350 2550);
PAINT MONO (-3350 2550);
DISPLAY INVISIBLE (-3350 2550);
FORCEPROP 1 LAST BODY_TYPE PLUMBING
J 0
(-3350 2500);
DISPLAY 1.234043 (-3350 2500);
PAINT GREEN (-3350 2500);
DISPLAY INVISIBLE (-3350 2500);
FORCEPROP 1 LAST HDL_TAP TRUE
J 0
(-3025 2425);
DISPLAY 1.234043 (-3025 2425);
PAINT GREEN (-3025 2425);
DISPLAY INVISIBLE (-3025 2425);
FORCEPROP 1 LAST PATH I143
J 0
(-3350 2550);
DISPLAY 0.936170 (-3350 2550);
PAINT GREEN (-3350 2550);
DISPLAY INVISIBLE (-3350 2550);
FORCEADD TAP..6
(-3350 2600);
FORCEPROP 3 LASTPIN (-3300 2600) SIG_NAME M_H_ECC<3>
J 0
(-3290 2610);
DISPLAY 0.659574 (-3290 2610);
PAINT MONO (-3290 2610);
DISPLAY INVISIBLE (-3290 2610);
FORCEPROP 1 LASTPIN (-3300 2600) BN 3
J 0
(-3350 2610);
DISPLAY 0.617021 (-3350 2610);
PAINT PINK (-3350 2610);
FORCEPROP 2 LAST CDS_LIB mstr_standard
J 0
(-3350 2600);
DISPLAY 0.787234 (-3350 2600);
PAINT MONO (-3350 2600);
DISPLAY INVISIBLE (-3350 2600);
FORCEPROP 1 LAST BODY_TYPE PLUMBING
J 0
(-3350 2550);
DISPLAY 1.234043 (-3350 2550);
PAINT GREEN (-3350 2550);
DISPLAY INVISIBLE (-3350 2550);
FORCEPROP 1 LAST HDL_TAP TRUE
J 0
(-3025 2475);
DISPLAY 1.234043 (-3025 2475);
PAINT GREEN (-3025 2475);
DISPLAY INVISIBLE (-3025 2475);
FORCEPROP 1 LAST PATH I144
J 0
(-3350 2600);
DISPLAY 0.936170 (-3350 2600);
PAINT GREEN (-3350 2600);
DISPLAY INVISIBLE (-3350 2600);
FORCEADD TAP..6
(-3350 2500);
FORCEPROP 3 LASTPIN (-3300 2500) SIG_NAME M_H_ECC<1>
J 0
(-3290 2510);
DISPLAY 0.659574 (-3290 2510);
PAINT MONO (-3290 2510);
DISPLAY INVISIBLE (-3290 2510);
FORCEPROP 1 LASTPIN (-3300 2500) BN 1
J 0
(-3350 2510);
DISPLAY 0.617021 (-3350 2510);
PAINT PINK (-3350 2510);
FORCEPROP 2 LAST CDS_LIB mstr_standard
J 0
(-3350 2500);
DISPLAY 0.787234 (-3350 2500);
PAINT MONO (-3350 2500);
DISPLAY INVISIBLE (-3350 2500);
FORCEPROP 1 LAST BODY_TYPE PLUMBING
J 0
(-3350 2450);
DISPLAY 1.234043 (-3350 2450);
PAINT GREEN (-3350 2450);
DISPLAY INVISIBLE (-3350 2450);
FORCEPROP 1 LAST HDL_TAP TRUE
J 0
(-3025 2375);
DISPLAY 1.234043 (-3025 2375);
PAINT GREEN (-3025 2375);
DISPLAY INVISIBLE (-3025 2375);
FORCEPROP 1 LAST PATH I145
J 0
(-3350 2500);
DISPLAY 0.936170 (-3350 2500);
PAINT GREEN (-3350 2500);
DISPLAY INVISIBLE (-3350 2500);
FORCEADD OFFPAGE..1
(-4000 2850);
FORCEPROP 2 LAST $XR1 80 
J 0
(-4341 2850);
DISPLAY 0.638298 (-4341 2850);
PAINT MONO (-4341 2850);
FORCEPROP 2 LAST $XR0 58 
J 0
(-4251 2850);
DISPLAY 0.638298 (-4251 2850);
PAINT MONO (-4251 2850);
FORCEPROP 2 LAST CDS_LIB mstr_standard
J 0
(-4000 2850);
DISPLAY 0.787234 (-4000 2850);
PAINT MONO (-4000 2850);
DISPLAY INVISIBLE (-4000 2850);
FORCEPROP 1 LAST OFFPAGE TRUE
J 0
(-3675 2725);
DISPLAY 0.936170 (-3675 2725);
PAINT GREEN (-3675 2725);
DISPLAY INVISIBLE (-3675 2725);
FORCEPROP 1 LAST COMMENT_BODY TRUE
J 0
(-3875 2750);
DISPLAY 0.936170 (-3875 2750);
PAINT GREEN (-3875 2750);
DISPLAY INVISIBLE (-3875 2750);
FORCEPROP 2 LAST PATH I146
J 0
(-3950 2925);
DISPLAY 0.787234 (-3950 2925);
PAINT MONO (-3950 2925);
DISPLAY INVISIBLE (-3950 2925);
FORCEADD OFFPAGE..1
(-4000 2200);
FORCEPROP 2 LAST $XR1 80 
J 0
(-4341 2200);
DISPLAY 0.638298 (-4341 2200);
PAINT MONO (-4341 2200);
FORCEPROP 2 LAST $XR0 58 
J 0
(-4251 2200);
DISPLAY 0.638298 (-4251 2200);
PAINT MONO (-4251 2200);
FORCEPROP 2 LAST CDS_LIB mstr_standard
J 0
(-4000 2200);
DISPLAY 0.787234 (-4000 2200);
PAINT MONO (-4000 2200);
DISPLAY INVISIBLE (-4000 2200);
FORCEPROP 1 LAST OFFPAGE TRUE
J 0
(-3675 2075);
DISPLAY 0.936170 (-3675 2075);
PAINT GREEN (-3675 2075);
DISPLAY INVISIBLE (-3675 2075);
FORCEPROP 1 LAST COMMENT_BODY TRUE
J 0
(-3875 2100);
DISPLAY 0.936170 (-3875 2100);
PAINT GREEN (-3875 2100);
DISPLAY INVISIBLE (-3875 2100);
FORCEPROP 2 LAST PATH I147
J 0
(-3950 2275);
DISPLAY 0.787234 (-3950 2275);
PAINT MONO (-3950 2275);
DISPLAY INVISIBLE (-3950 2275);
FORCEADD OFFPAGE..5
(-4025 2250);
FORCEPROP 2 LAST $XR1 58 
J 0
(-4339 2250);
DISPLAY 0.638298 (-4339 2250);
PAINT MONO (-4339 2250);
FORCEPROP 2 LAST $XR0 80 
J 0
(-4249 2250);
DISPLAY 0.638298 (-4249 2250);
PAINT MONO (-4249 2250);
FORCEPROP 2 LAST CDS_LIB mstr_standard
J 0
(-4025 2250);
DISPLAY 0.787234 (-4025 2250);
PAINT MONO (-4025 2250);
DISPLAY INVISIBLE (-4025 2250);
FORCEPROP 1 LAST OFFPAGE TRUE
J 0
(-3700 2125);
DISPLAY 1.404255 (-3700 2125);
PAINT GREEN (-3700 2125);
DISPLAY INVISIBLE (-3700 2125);
FORCEPROP 1 LAST COMMENT_BODY TRUE
J 0
(-3925 2175);
DISPLAY 1.404255 (-3925 2175);
PAINT GREEN (-3925 2175);
DISPLAY INVISIBLE (-3925 2175);
FORCEPROP 2 LAST PATH I148
J 0
(-3975 2325);
DISPLAY 0.787234 (-3975 2325);
PAINT MONO (-3975 2325);
DISPLAY INVISIBLE (-3975 2325);
FORCEADD OFFPAGE..1
(-4000 2800);
FORCEPROP 2 LAST $XR5 82 
J 0
(-4701 2800);
DISPLAY 0.638298 (-4701 2800);
PAINT MONO (-4701 2800);
FORCEPROP 2 LAST $XR4 81 
J 0
(-4611 2800);
DISPLAY 0.638298 (-4611 2800);
PAINT MONO (-4611 2800);
FORCEPROP 2 LAST $XR3 80 
J 0
(-4521 2800);
DISPLAY 0.638298 (-4521 2800);
PAINT MONO (-4521 2800);
FORCEPROP 2 LAST $XR2 78 
J 0
(-4431 2800);
DISPLAY 0.638298 (-4431 2800);
PAINT MONO (-4431 2800);
FORCEPROP 2 LAST $XR1 77 
J 0
(-4341 2800);
DISPLAY 0.638298 (-4341 2800);
PAINT MONO (-4341 2800);
FORCEPROP 2 LAST $XR0 55 
J 0
(-4251 2800);
DISPLAY 0.638298 (-4251 2800);
PAINT MONO (-4251 2800);
FORCEPROP 2 LAST CDS_LIB mstr_standard
J 0
(-4000 2800);
DISPLAY 0.787234 (-4000 2800);
PAINT MONO (-4000 2800);
DISPLAY INVISIBLE (-4000 2800);
FORCEPROP 1 LAST OFFPAGE TRUE
J 0
(-3675 2675);
DISPLAY 0.936170 (-3675 2675);
PAINT GREEN (-3675 2675);
DISPLAY INVISIBLE (-3675 2675);
FORCEPROP 1 LAST COMMENT_BODY TRUE
J 0
(-3875 2700);
DISPLAY 0.936170 (-3875 2700);
PAINT GREEN (-3875 2700);
DISPLAY INVISIBLE (-3875 2700);
FORCEPROP 2 LAST PATH I149
J 0
(-3950 2875);
DISPLAY 0.787234 (-3950 2875);
PAINT MONO (-3950 2875);
DISPLAY INVISIBLE (-3950 2875);
FORCEADD OFFPAGE..6
(-4000 2900);
FORCEPROP 2 LAST $XR1 80 
J 0
(-4339 2900);
DISPLAY 0.638298 (-4339 2900);
PAINT MONO (-4339 2900);
FORCEPROP 2 LAST $XR0 58 
J 0
(-4249 2900);
DISPLAY 0.638298 (-4249 2900);
PAINT MONO (-4249 2900);
FORCEPROP 2 LAST CDS_LIB mstr_standard
J 0
(-4000 2900);
DISPLAY 0.787234 (-4000 2900);
PAINT MONO (-4000 2900);
DISPLAY INVISIBLE (-4000 2900);
FORCEPROP 1 LAST OFFPAGE TRUE
J 0
(-3675 2775);
DISPLAY 0.936170 (-3675 2775);
PAINT GREEN (-3675 2775);
DISPLAY INVISIBLE (-3675 2775);
FORCEPROP 1 LAST COMMENT_BODY TRUE
J 0
(-3900 2825);
DISPLAY 0.936170 (-3900 2825);
PAINT GREEN (-3900 2825);
DISPLAY INVISIBLE (-3900 2825);
FORCEPROP 2 LAST PATH I150
J 0
(-3950 2975);
DISPLAY 0.787234 (-3950 2975);
PAINT MONO (-3950 2975);
DISPLAY INVISIBLE (-3950 2975);
FORCEADD TAP..6
(-3350 3700);
FORCEPROP 3 LASTPIN (-3300 3700) SIG_NAME M_H_CLK_DP<1>
J 0
(-3290 3710);
DISPLAY 0.659574 (-3290 3710);
PAINT MONO (-3290 3710);
DISPLAY INVISIBLE (-3290 3710);
FORCEPROP 1 LASTPIN (-3300 3700) BN 1
J 0
(-3350 3710);
DISPLAY 0.617021 (-3350 3710);
PAINT PINK (-3350 3710);
FORCEPROP 2 LAST CDS_LIB mstr_standard
J 0
(-3350 3700);
DISPLAY 0.787234 (-3350 3700);
PAINT MONO (-3350 3700);
DISPLAY INVISIBLE (-3350 3700);
FORCEPROP 1 LAST BODY_TYPE PLUMBING
J 0
(-3350 3650);
DISPLAY 1.234043 (-3350 3650);
PAINT GREEN (-3350 3650);
DISPLAY INVISIBLE (-3350 3650);
FORCEPROP 1 LAST HDL_TAP TRUE
J 0
(-3025 3575);
DISPLAY 1.234043 (-3025 3575);
PAINT GREEN (-3025 3575);
DISPLAY INVISIBLE (-3025 3575);
FORCEPROP 1 LAST PATH I152
J 0
(-3350 3700);
DISPLAY 0.936170 (-3350 3700);
PAINT GREEN (-3350 3700);
DISPLAY INVISIBLE (-3350 3700);
FORCEADD TAP..6
(-3350 3600);
FORCEPROP 3 LASTPIN (-3300 3600) SIG_NAME M_H_CLK_DP<0>
J 0
(-3290 3610);
DISPLAY 0.659574 (-3290 3610);
PAINT MONO (-3290 3610);
DISPLAY INVISIBLE (-3290 3610);
FORCEPROP 1 LASTPIN (-3300 3600) BN 0
J 0
(-3350 3610);
DISPLAY 0.617021 (-3350 3610);
PAINT PINK (-3350 3610);
FORCEPROP 2 LAST CDS_LIB mstr_standard
J 0
(-3350 3600);
DISPLAY 0.787234 (-3350 3600);
PAINT MONO (-3350 3600);
DISPLAY INVISIBLE (-3350 3600);
FORCEPROP 1 LAST BODY_TYPE PLUMBING
J 0
(-3350 3550);
DISPLAY 1.234043 (-3350 3550);
PAINT GREEN (-3350 3550);
DISPLAY INVISIBLE (-3350 3550);
FORCEPROP 1 LAST HDL_TAP TRUE
J 0
(-3025 3475);
DISPLAY 1.234043 (-3025 3475);
PAINT GREEN (-3025 3475);
DISPLAY INVISIBLE (-3025 3475);
FORCEPROP 1 LAST PATH I153
J 0
(-3350 3600);
DISPLAY 0.936170 (-3350 3600);
PAINT GREEN (-3350 3600);
DISPLAY INVISIBLE (-3350 3600);
FORCEADD TAP..6
(-3550 3650);
FORCEPROP 3 LASTPIN (-3500 3650) SIG_NAME M_H_CLK_DN<1>
J 0
(-3490 3660);
DISPLAY 0.659574 (-3490 3660);
PAINT MONO (-3490 3660);
DISPLAY INVISIBLE (-3490 3660);
FORCEPROP 1 LASTPIN (-3500 3650) BN 1
J 0
(-3550 3660);
DISPLAY 0.617021 (-3550 3660);
PAINT PINK (-3550 3660);
FORCEPROP 2 LAST CDS_LIB mstr_standard
J 0
(-3550 3650);
DISPLAY 0.787234 (-3550 3650);
PAINT MONO (-3550 3650);
DISPLAY INVISIBLE (-3550 3650);
FORCEPROP 1 LAST BODY_TYPE PLUMBING
J 0
(-3550 3600);
DISPLAY 1.234043 (-3550 3600);
PAINT GREEN (-3550 3600);
DISPLAY INVISIBLE (-3550 3600);
FORCEPROP 1 LAST HDL_TAP TRUE
J 0
(-3225 3525);
DISPLAY 1.234043 (-3225 3525);
PAINT GREEN (-3225 3525);
DISPLAY INVISIBLE (-3225 3525);
FORCEPROP 1 LAST PATH I154
J 0
(-3550 3650);
DISPLAY 0.936170 (-3550 3650);
PAINT GREEN (-3550 3650);
DISPLAY INVISIBLE (-3550 3650);
FORCEADD TAP..6
(-3550 3550);
FORCEPROP 3 LASTPIN (-3500 3550) SIG_NAME M_H_CLK_DN<0>
J 0
(-3490 3560);
DISPLAY 0.659574 (-3490 3560);
PAINT MONO (-3490 3560);
DISPLAY INVISIBLE (-3490 3560);
FORCEPROP 1 LASTPIN (-3500 3550) BN 0
J 0
(-3550 3560);
DISPLAY 0.617021 (-3550 3560);
PAINT PINK (-3550 3560);
FORCEPROP 2 LAST CDS_LIB mstr_standard
J 0
(-3550 3550);
DISPLAY 0.787234 (-3550 3550);
PAINT MONO (-3550 3550);
DISPLAY INVISIBLE (-3550 3550);
FORCEPROP 1 LAST BODY_TYPE PLUMBING
J 0
(-3550 3500);
DISPLAY 1.234043 (-3550 3500);
PAINT GREEN (-3550 3500);
DISPLAY INVISIBLE (-3550 3500);
FORCEPROP 1 LAST HDL_TAP TRUE
J 0
(-3225 3425);
DISPLAY 1.234043 (-3225 3425);
PAINT GREEN (-3225 3425);
DISPLAY INVISIBLE (-3225 3425);
FORCEPROP 1 LAST PATH I155
J 0
(-3550 3550);
DISPLAY 0.936170 (-3550 3550);
PAINT GREEN (-3550 3550);
DISPLAY INVISIBLE (-3550 3550);
FORCEADD OFFPAGE..1
(-4000 3700);
FORCEPROP 2 LAST $XR1 80 
J 0
(-4341 3700);
DISPLAY 0.638298 (-4341 3700);
PAINT MONO (-4341 3700);
FORCEPROP 2 LAST $XR0 58 
J 0
(-4251 3700);
DISPLAY 0.638298 (-4251 3700);
PAINT MONO (-4251 3700);
FORCEPROP 2 LAST CDS_LIB mstr_standard
J 0
(-4000 3700);
DISPLAY 0.787234 (-4000 3700);
PAINT MONO (-4000 3700);
DISPLAY INVISIBLE (-4000 3700);
FORCEPROP 1 LAST OFFPAGE TRUE
J 0
(-3675 3575);
DISPLAY 0.936170 (-3675 3575);
PAINT GREEN (-3675 3575);
DISPLAY INVISIBLE (-3675 3575);
FORCEPROP 1 LAST COMMENT_BODY TRUE
J 0
(-3875 3600);
DISPLAY 0.936170 (-3875 3600);
PAINT GREEN (-3875 3600);
DISPLAY INVISIBLE (-3875 3600);
FORCEPROP 2 LAST PATH I156
J 0
(-3950 3775);
DISPLAY 0.787234 (-3950 3775);
PAINT MONO (-3950 3775);
DISPLAY INVISIBLE (-3950 3775);
FORCEADD OFFPAGE..1
(-4000 3750);
FORCEPROP 2 LAST $XR1 80 
J 0
(-4341 3750);
DISPLAY 0.638298 (-4341 3750);
PAINT MONO (-4341 3750);
FORCEPROP 2 LAST $XR0 58 
J 0
(-4251 3750);
DISPLAY 0.638298 (-4251 3750);
PAINT MONO (-4251 3750);
FORCEPROP 2 LAST CDS_LIB mstr_standard
J 0
(-4000 3750);
DISPLAY 0.787234 (-4000 3750);
PAINT MONO (-4000 3750);
DISPLAY INVISIBLE (-4000 3750);
FORCEPROP 1 LAST OFFPAGE TRUE
J 0
(-3675 3625);
DISPLAY 0.936170 (-3675 3625);
PAINT GREEN (-3675 3625);
DISPLAY INVISIBLE (-3675 3625);
FORCEPROP 1 LAST COMMENT_BODY TRUE
J 0
(-3875 3650);
DISPLAY 0.936170 (-3875 3650);
PAINT GREEN (-3875 3650);
DISPLAY INVISIBLE (-3875 3650);
FORCEPROP 2 LAST PATH I157
J 0
(-3950 3825);
DISPLAY 0.787234 (-3950 3825);
PAINT MONO (-3950 3825);
DISPLAY INVISIBLE (-3950 3825);
FORCEADD TAP..6
(-3350 3400);
FORCEPROP 3 LASTPIN (-3300 3400) SIG_NAME M_H_CS_N<3>
J 0
(-3290 3410);
DISPLAY 0.659574 (-3290 3410);
PAINT MONO (-3290 3410);
DISPLAY INVISIBLE (-3290 3410);
FORCEPROP 1 LASTPIN (-3300 3400) BN 3
J 0
(-3350 3410);
DISPLAY 0.617021 (-3350 3410);
PAINT PINK (-3350 3410);
FORCEPROP 2 LAST CDS_LIB mstr_standard
J 0
(-3350 3400);
DISPLAY 0.787234 (-3350 3400);
PAINT MONO (-3350 3400);
DISPLAY INVISIBLE (-3350 3400);
FORCEPROP 1 LAST BODY_TYPE PLUMBING
J 0
(-3350 3350);
DISPLAY 1.234043 (-3350 3350);
PAINT GREEN (-3350 3350);
DISPLAY INVISIBLE (-3350 3350);
FORCEPROP 1 LAST HDL_TAP TRUE
J 0
(-3025 3275);
DISPLAY 1.234043 (-3025 3275);
PAINT GREEN (-3025 3275);
DISPLAY INVISIBLE (-3025 3275);
FORCEPROP 1 LAST PATH I158
J 0
(-3350 3400);
DISPLAY 0.936170 (-3350 3400);
PAINT GREEN (-3350 3400);
DISPLAY INVISIBLE (-3350 3400);
FORCEADD TAP..6
(-3350 3350);
FORCEPROP 3 LASTPIN (-3300 3350) SIG_NAME M_H_CS_N<2>
J 0
(-3290 3360);
DISPLAY 0.659574 (-3290 3360);
PAINT MONO (-3290 3360);
DISPLAY INVISIBLE (-3290 3360);
FORCEPROP 1 LASTPIN (-3300 3350) BN 2
J 0
(-3350 3360);
DISPLAY 0.617021 (-3350 3360);
PAINT PINK (-3350 3360);
FORCEPROP 2 LAST CDS_LIB mstr_standard
J 0
(-3350 3350);
DISPLAY 0.787234 (-3350 3350);
PAINT MONO (-3350 3350);
DISPLAY INVISIBLE (-3350 3350);
FORCEPROP 1 LAST BODY_TYPE PLUMBING
J 0
(-3350 3300);
DISPLAY 1.234043 (-3350 3300);
PAINT GREEN (-3350 3300);
DISPLAY INVISIBLE (-3350 3300);
FORCEPROP 1 LAST HDL_TAP TRUE
J 0
(-3025 3225);
DISPLAY 1.234043 (-3025 3225);
PAINT GREEN (-3025 3225);
DISPLAY INVISIBLE (-3025 3225);
FORCEPROP 1 LAST PATH I159
J 0
(-3350 3350);
DISPLAY 0.936170 (-3350 3350);
PAINT GREEN (-3350 3350);
DISPLAY INVISIBLE (-3350 3350);
FORCEADD PVTT_GHJ..1
(-1300 2700);
FORCEPROP 3 LASTPIN (-1300 2650) SIG_NAME PVTT_GHJ\g
J 0
(-1290 2660);
DISPLAY 0.659574 (-1290 2660);
PAINT MONO (-1290 2660);
DISPLAY INVISIBLE (-1290 2660);
FORCEPROP 1 LAST VOLTAGE 0.6V
J 0
(-1345 2657);
DISPLAY 0.340426 (-1345 2657);
PAINT SKYBLUE (-1345 2657);
DISPLAY INVISIBLE (-1345 2657);
FORCEPROP 2 LAST BOM_COST MEM
J 0
(-1300 2705);
PAINT ORANGE (-1300 2705);
DISPLAY INVISIBLE (-1300 2705);
FORCEPROP 2 LAST CDS_LIB mstr_symbols
J 0
(-1300 2700);
PAINT ORANGE (-1300 2700);
DISPLAY INVISIBLE (-1300 2700);
FORCEPROP 1 LAST BODY_TYPE PLUMBING
J 0
(-1345 2657);
DISPLAY 0.340426 (-1345 2657);
PAINT GREEN (-1345 2657);
DISPLAY INVISIBLE (-1345 2657);
FORCEPROP 1 LAST PATH I16
J 0
(-1250 2725);
DISPLAY 0.872340 (-1250 2725);
PAINT AQUA (-1250 2725);
DISPLAY INVISIBLE (-1250 2725);
FORCEPROP 2 LAST ROOM DDR4_CH_H
J 0
(-1300 2800);
DISPLAY 0.787234 (-1300 2800);
PAINT ORANGE (-1300 2800);
DISPLAY INVISIBLE (-1300 2800);
FORCEPROP 1 LAST HDL_POWER PVTT_GHJ
J 1
(-1300 2750);
DISPLAY 0.872340 (-1300 2750);
PAINT GREEN (-1300 2750);
DISPLAY INVISIBLE (-1300 2750);
FORCEADD TAP..6
(-3350 3300);
FORCEPROP 3 LASTPIN (-3300 3300) SIG_NAME M_H_CS_N<1>
J 0
(-3290 3310);
DISPLAY 0.659574 (-3290 3310);
PAINT MONO (-3290 3310);
DISPLAY INVISIBLE (-3290 3310);
FORCEPROP 1 LASTPIN (-3300 3300) BN 1
J 0
(-3350 3310);
DISPLAY 0.617021 (-3350 3310);
PAINT PINK (-3350 3310);
FORCEPROP 2 LAST CDS_LIB mstr_standard
J 0
(-3350 3300);
DISPLAY 0.787234 (-3350 3300);
PAINT MONO (-3350 3300);
DISPLAY INVISIBLE (-3350 3300);
FORCEPROP 1 LAST BODY_TYPE PLUMBING
J 0
(-3350 3250);
DISPLAY 1.234043 (-3350 3250);
PAINT GREEN (-3350 3250);
DISPLAY INVISIBLE (-3350 3250);
FORCEPROP 1 LAST HDL_TAP TRUE
J 0
(-3025 3175);
DISPLAY 1.234043 (-3025 3175);
PAINT GREEN (-3025 3175);
DISPLAY INVISIBLE (-3025 3175);
FORCEPROP 1 LAST PATH I160
J 0
(-3350 3300);
DISPLAY 0.936170 (-3350 3300);
PAINT GREEN (-3350 3300);
DISPLAY INVISIBLE (-3350 3300);
FORCEADD TAP..6
(-3350 3250);
FORCEPROP 3 LASTPIN (-3300 3250) SIG_NAME M_H_CS_N<0>
J 0
(-3290 3260);
DISPLAY 0.659574 (-3290 3260);
PAINT MONO (-3290 3260);
DISPLAY INVISIBLE (-3290 3260);
FORCEPROP 1 LASTPIN (-3300 3250) BN 0
J 0
(-3350 3260);
DISPLAY 0.617021 (-3350 3260);
PAINT PINK (-3350 3260);
FORCEPROP 2 LAST CDS_LIB mstr_standard
J 0
(-3350 3250);
DISPLAY 0.787234 (-3350 3250);
PAINT MONO (-3350 3250);
DISPLAY INVISIBLE (-3350 3250);
FORCEPROP 1 LAST BODY_TYPE PLUMBING
J 0
(-3350 3200);
DISPLAY 1.234043 (-3350 3200);
PAINT GREEN (-3350 3200);
DISPLAY INVISIBLE (-3350 3200);
FORCEPROP 1 LAST HDL_TAP TRUE
J 0
(-3025 3125);
DISPLAY 1.234043 (-3025 3125);
PAINT GREEN (-3025 3125);
DISPLAY INVISIBLE (-3025 3125);
FORCEPROP 1 LAST PATH I161
J 0
(-3350 3250);
DISPLAY 0.936170 (-3350 3250);
PAINT GREEN (-3350 3250);
DISPLAY INVISIBLE (-3350 3250);
FORCEADD TAP..6
(-3350 3150);
FORCEPROP 3 LASTPIN (-3300 3150) SIG_NAME M_H_CKE<1>
J 0
(-3290 3160);
DISPLAY 0.659574 (-3290 3160);
PAINT MONO (-3290 3160);
DISPLAY INVISIBLE (-3290 3160);
FORCEPROP 1 LASTPIN (-3300 3150) BN 1
J 0
(-3350 3160);
DISPLAY 0.617021 (-3350 3160);
PAINT PINK (-3350 3160);
FORCEPROP 2 LAST CDS_LIB mstr_standard
J 0
(-3350 3150);
DISPLAY 0.787234 (-3350 3150);
PAINT MONO (-3350 3150);
DISPLAY INVISIBLE (-3350 3150);
FORCEPROP 1 LAST BODY_TYPE PLUMBING
J 0
(-3350 3100);
DISPLAY 1.234043 (-3350 3100);
PAINT GREEN (-3350 3100);
DISPLAY INVISIBLE (-3350 3100);
FORCEPROP 1 LAST HDL_TAP TRUE
J 0
(-3025 3025);
DISPLAY 1.234043 (-3025 3025);
PAINT GREEN (-3025 3025);
DISPLAY INVISIBLE (-3025 3025);
FORCEPROP 1 LAST PATH I162
J 0
(-3350 3150);
DISPLAY 0.936170 (-3350 3150);
PAINT GREEN (-3350 3150);
DISPLAY INVISIBLE (-3350 3150);
FORCEADD TAP..6
(-3350 3100);
FORCEPROP 3 LASTPIN (-3300 3100) SIG_NAME M_H_CKE<0>
J 0
(-3290 3110);
DISPLAY 0.659574 (-3290 3110);
PAINT MONO (-3290 3110);
DISPLAY INVISIBLE (-3290 3110);
FORCEPROP 1 LASTPIN (-3300 3100) BN 0
J 0
(-3350 3110);
DISPLAY 0.617021 (-3350 3110);
PAINT PINK (-3350 3110);
FORCEPROP 2 LAST CDS_LIB mstr_standard
J 0
(-3350 3100);
DISPLAY 0.787234 (-3350 3100);
PAINT MONO (-3350 3100);
DISPLAY INVISIBLE (-3350 3100);
FORCEPROP 1 LAST BODY_TYPE PLUMBING
J 0
(-3350 3050);
DISPLAY 1.234043 (-3350 3050);
PAINT GREEN (-3350 3050);
DISPLAY INVISIBLE (-3350 3050);
FORCEPROP 1 LAST HDL_TAP TRUE
J 0
(-3025 2975);
DISPLAY 1.234043 (-3025 2975);
PAINT GREEN (-3025 2975);
DISPLAY INVISIBLE (-3025 2975);
FORCEPROP 1 LAST PATH I163
J 0
(-3350 3100);
DISPLAY 0.936170 (-3350 3100);
PAINT GREEN (-3350 3100);
DISPLAY INVISIBLE (-3350 3100);
FORCEADD TAP..6
(-3350 3000);
FORCEPROP 3 LASTPIN (-3300 3000) SIG_NAME M_H_ODT<1>
J 0
(-3290 3010);
DISPLAY 0.659574 (-3290 3010);
PAINT MONO (-3290 3010);
DISPLAY INVISIBLE (-3290 3010);
FORCEPROP 1 LASTPIN (-3300 3000) BN 1
J 0
(-3350 3010);
DISPLAY 0.617021 (-3350 3010);
PAINT PINK (-3350 3010);
FORCEPROP 2 LAST CDS_LIB mstr_standard
J 0
(-3350 3000);
DISPLAY 0.787234 (-3350 3000);
PAINT MONO (-3350 3000);
DISPLAY INVISIBLE (-3350 3000);
FORCEPROP 1 LAST BODY_TYPE PLUMBING
J 0
(-3350 2950);
DISPLAY 1.234043 (-3350 2950);
PAINT GREEN (-3350 2950);
DISPLAY INVISIBLE (-3350 2950);
FORCEPROP 1 LAST HDL_TAP TRUE
J 0
(-3025 2875);
DISPLAY 1.234043 (-3025 2875);
PAINT GREEN (-3025 2875);
DISPLAY INVISIBLE (-3025 2875);
FORCEPROP 1 LAST PATH I164
J 0
(-3350 3000);
DISPLAY 0.936170 (-3350 3000);
PAINT GREEN (-3350 3000);
DISPLAY INVISIBLE (-3350 3000);
FORCEADD OFFPAGE..1
(-4000 3450);
FORCEPROP 2 LAST $XR1 80 
J 0
(-4341 3450);
DISPLAY 0.638298 (-4341 3450);
PAINT MONO (-4341 3450);
FORCEPROP 2 LAST $XR0 58 
J 0
(-4251 3450);
DISPLAY 0.638298 (-4251 3450);
PAINT MONO (-4251 3450);
FORCEPROP 2 LAST CDS_LIB mstr_standard
J 0
(-4000 3450);
DISPLAY 0.787234 (-4000 3450);
PAINT MONO (-4000 3450);
DISPLAY INVISIBLE (-4000 3450);
FORCEPROP 1 LAST OFFPAGE TRUE
J 0
(-3675 3325);
DISPLAY 0.936170 (-3675 3325);
PAINT GREEN (-3675 3325);
DISPLAY INVISIBLE (-3675 3325);
FORCEPROP 1 LAST COMMENT_BODY TRUE
J 0
(-3875 3350);
DISPLAY 0.936170 (-3875 3350);
PAINT GREEN (-3875 3350);
DISPLAY INVISIBLE (-3875 3350);
FORCEPROP 2 LAST PATH I165
J 0
(-3950 3525);
DISPLAY 0.787234 (-3950 3525);
PAINT MONO (-3950 3525);
DISPLAY INVISIBLE (-3950 3525);
FORCEADD OFFPAGE..1
(-4000 3200);
FORCEPROP 2 LAST $XR1 80 
J 0
(-4341 3200);
DISPLAY 0.638298 (-4341 3200);
PAINT MONO (-4341 3200);
FORCEPROP 2 LAST $XR0 58 
J 0
(-4251 3200);
DISPLAY 0.638298 (-4251 3200);
PAINT MONO (-4251 3200);
FORCEPROP 2 LAST CDS_LIB mstr_standard
J 0
(-4000 3200);
DISPLAY 0.787234 (-4000 3200);
PAINT MONO (-4000 3200);
DISPLAY INVISIBLE (-4000 3200);
FORCEPROP 1 LAST OFFPAGE TRUE
J 0
(-3675 3075);
DISPLAY 0.936170 (-3675 3075);
PAINT GREEN (-3675 3075);
DISPLAY INVISIBLE (-3675 3075);
FORCEPROP 1 LAST COMMENT_BODY TRUE
J 0
(-3875 3100);
DISPLAY 0.936170 (-3875 3100);
PAINT GREEN (-3875 3100);
DISPLAY INVISIBLE (-3875 3100);
FORCEPROP 2 LAST PATH I166
J 0
(-3950 3275);
DISPLAY 0.787234 (-3950 3275);
PAINT MONO (-3950 3275);
DISPLAY INVISIBLE (-3950 3275);
FORCEADD OFFPAGE..1
(-4000 3050);
FORCEPROP 2 LAST $XR1 80 
J 0
(-4341 3050);
DISPLAY 0.638298 (-4341 3050);
PAINT MONO (-4341 3050);
FORCEPROP 2 LAST $XR0 58 
J 0
(-4251 3050);
DISPLAY 0.638298 (-4251 3050);
PAINT MONO (-4251 3050);
FORCEPROP 2 LAST CDS_LIB mstr_standard
J 0
(-4000 3050);
DISPLAY 0.787234 (-4000 3050);
PAINT MONO (-4000 3050);
DISPLAY INVISIBLE (-4000 3050);
FORCEPROP 1 LAST OFFPAGE TRUE
J 0
(-3675 2925);
DISPLAY 0.936170 (-3675 2925);
PAINT GREEN (-3675 2925);
DISPLAY INVISIBLE (-3675 2925);
FORCEPROP 1 LAST COMMENT_BODY TRUE
J 0
(-3875 2950);
DISPLAY 0.936170 (-3875 2950);
PAINT GREEN (-3875 2950);
DISPLAY INVISIBLE (-3875 2950);
FORCEPROP 2 LAST PATH I167
J 0
(-3950 3125);
DISPLAY 0.787234 (-3950 3125);
PAINT MONO (-3950 3125);
DISPLAY INVISIBLE (-3950 3125);
FORCEADD TAP..6
(-3350 2950);
FORCEPROP 3 LASTPIN (-3300 2950) SIG_NAME M_H_ODT<0>
J 0
(-3290 2960);
DISPLAY 0.659574 (-3290 2960);
PAINT MONO (-3290 2960);
DISPLAY INVISIBLE (-3290 2960);
FORCEPROP 1 LASTPIN (-3300 2950) BN 0
J 0
(-3350 2960);
DISPLAY 0.617021 (-3350 2960);
PAINT PINK (-3350 2960);
FORCEPROP 2 LAST CDS_LIB mstr_standard
J 0
(-3350 2950);
DISPLAY 0.787234 (-3350 2950);
PAINT MONO (-3350 2950);
DISPLAY INVISIBLE (-3350 2950);
FORCEPROP 1 LAST BODY_TYPE PLUMBING
J 0
(-3350 2900);
DISPLAY 1.234043 (-3350 2900);
PAINT GREEN (-3350 2900);
DISPLAY INVISIBLE (-3350 2900);
FORCEPROP 1 LAST HDL_TAP TRUE
J 0
(-3025 2825);
DISPLAY 1.234043 (-3025 2825);
PAINT GREEN (-3025 2825);
DISPLAY INVISIBLE (-3025 2825);
FORCEPROP 1 LAST PATH I168
J 0
(-3350 2950);
DISPLAY 0.936170 (-3350 2950);
PAINT GREEN (-3350 2950);
DISPLAY INVISIBLE (-3350 2950);
FORCEADD SCONN288_H44441004..4
(-450 2000);
FORCEPROP 1 LAST PART_NUMBER H44441-004
J 0
(-900 950);
DISPLAY 0.617021 (-900 950);
PAINT BLUE (-900 950);
FORCEPROP 1 LAST LOCATION J1G2
J 0
(-900 3100);
DISPLAY 0.617021 (-900 3100);
PAINT AQUA (-900 3100);
FORCEPROP 1 LAST MATERIAL SCONN
J 0
(-900 3050);
DISPLAY 0.617021 (-900 3050);
PAINT SKYBLUE (-900 3050);
FORCEPROP 2 LASTPIN (-950 2550) $PN 77
J 2
(-960 2560);
DISPLAY 0.617021 (-960 2560);
PAINT ORANGE (-960 2560);
FORCEPROP 2 LASTPIN (-950 2500) $PN 221
J 2
(-960 2510);
DISPLAY 0.617021 (-960 2510);
PAINT ORANGE (-960 2510);
FORCEPROP 2 LASTPIN (-950 2850) $PN 142
J 2
(-960 2860);
DISPLAY 0.617021 (-960 2860);
PAINT ORANGE (-960 2860);
FORCEPROP 2 LASTPIN (-950 2800) $PN 143
J 2
(-960 2810);
DISPLAY 0.617021 (-960 2810);
PAINT ORANGE (-960 2810);
FORCEPROP 2 LASTPIN (-950 2750) $PN 288
J 2
(-960 2760);
DISPLAY 0.617021 (-960 2760);
PAINT ORANGE (-960 2760);
FORCEPROP 2 LASTPIN (-950 2700) $PN 286
J 2
(-960 2710);
DISPLAY 0.617021 (-960 2710);
PAINT ORANGE (-960 2710);
FORCEPROP 2 LASTPIN (-950 2650) $PN 287
J 2
(-960 2660);
DISPLAY 0.617021 (-960 2660);
PAINT ORANGE (-960 2660);
FORCEPROP 2 LASTPIN (-950 2400) $PN 59
J 2
(-960 2410);
DISPLAY 0.617021 (-960 2410);
PAINT ORANGE (-960 2410);
FORCEPROP 2 LASTPIN (-950 2350) $PN 61
J 2
(-960 2360);
DISPLAY 0.617021 (-960 2360);
PAINT ORANGE (-960 2360);
FORCEPROP 2 LASTPIN (-950 2300) $PN 64
J 2
(-960 2310);
DISPLAY 0.617021 (-960 2310);
PAINT ORANGE (-960 2310);
FORCEPROP 2 LASTPIN (-950 2250) $PN 67
J 2
(-960 2260);
DISPLAY 0.617021 (-960 2260);
PAINT ORANGE (-960 2260);
FORCEPROP 2 LASTPIN (-950 2200) $PN 70
J 2
(-960 2210);
DISPLAY 0.617021 (-960 2210);
PAINT ORANGE (-960 2210);
FORCEPROP 2 LASTPIN (-950 2150) $PN 73
J 2
(-960 2160);
DISPLAY 0.617021 (-960 2160);
PAINT ORANGE (-960 2160);
FORCEPROP 2 LASTPIN (-950 2100) $PN 76
J 2
(-960 2110);
DISPLAY 0.617021 (-960 2110);
PAINT ORANGE (-960 2110);
FORCEPROP 2 LASTPIN (-950 2050) $PN 80
J 2
(-960 2060);
DISPLAY 0.617021 (-960 2060);
PAINT ORANGE (-960 2060);
FORCEPROP 2 LASTPIN (-950 2000) $PN 83
J 2
(-960 2010);
DISPLAY 0.617021 (-960 2010);
PAINT ORANGE (-960 2010);
FORCEPROP 2 LASTPIN (-950 1950) $PN 85
J 2
(-960 1960);
DISPLAY 0.617021 (-960 1960);
PAINT ORANGE (-960 1960);
FORCEPROP 2 LASTPIN (-950 1900) $PN 88
J 2
(-960 1910);
DISPLAY 0.617021 (-960 1910);
PAINT ORANGE (-960 1910);
FORCEPROP 2 LASTPIN (-950 1850) $PN 90
J 2
(-960 1860);
DISPLAY 0.617021 (-960 1860);
PAINT ORANGE (-960 1860);
FORCEPROP 2 LASTPIN (-950 1800) $PN 92
J 2
(-960 1810);
DISPLAY 0.617021 (-960 1810);
PAINT ORANGE (-960 1810);
FORCEPROP 2 LASTPIN (-950 1750) $PN 204
J 2
(-960 1760);
DISPLAY 0.617021 (-960 1760);
PAINT ORANGE (-960 1760);
FORCEPROP 2 LASTPIN (-950 1700) $PN 206
J 2
(-960 1710);
DISPLAY 0.617021 (-960 1710);
PAINT ORANGE (-960 1710);
FORCEPROP 2 LASTPIN (-950 1650) $PN 209
J 2
(-960 1660);
DISPLAY 0.617021 (-960 1660);
PAINT ORANGE (-960 1660);
FORCEPROP 2 LASTPIN (-950 1600) $PN 212
J 2
(-960 1610);
DISPLAY 0.617021 (-960 1610);
PAINT ORANGE (-960 1610);
FORCEPROP 2 LASTPIN (-950 1550) $PN 215
J 2
(-960 1560);
DISPLAY 0.617021 (-960 1560);
PAINT ORANGE (-960 1560);
FORCEPROP 2 LASTPIN (-950 1500) $PN 217
J 2
(-960 1510);
DISPLAY 0.617021 (-960 1510);
PAINT ORANGE (-960 1510);
FORCEPROP 2 LASTPIN (-950 1450) $PN 220
J 2
(-960 1460);
DISPLAY 0.617021 (-960 1460);
PAINT ORANGE (-960 1460);
FORCEPROP 2 LASTPIN (-950 1400) $PN 223
J 2
(-960 1410);
DISPLAY 0.617021 (-960 1410);
PAINT ORANGE (-960 1410);
FORCEPROP 2 LASTPIN (-950 1350) $PN 226
J 2
(-960 1360);
DISPLAY 0.617021 (-960 1360);
PAINT ORANGE (-960 1360);
FORCEPROP 2 LASTPIN (-950 1300) $PN 229
J 2
(-960 1310);
DISPLAY 0.617021 (-960 1310);
PAINT ORANGE (-960 1310);
FORCEPROP 2 LASTPIN (-950 1250) $PN 231
J 2
(-960 1260);
DISPLAY 0.617021 (-960 1260);
PAINT ORANGE (-960 1260);
FORCEPROP 2 LASTPIN (-950 1200) $PN 233
J 2
(-960 1210);
DISPLAY 0.617021 (-960 1210);
PAINT ORANGE (-960 1210);
FORCEPROP 2 LASTPIN (-950 1150) $PN 236
J 2
(-960 1160);
DISPLAY 0.617021 (-960 1160);
PAINT ORANGE (-960 1160);
FORCEPROP 2 LASTPIN (50 2850) $PN 1
J 0
(60 2860);
DISPLAY 0.617021 (60 2860);
PAINT ORANGE (60 2860);
FORCEPROP 2 LASTPIN (50 2800) $PN 145
J 0
(60 2810);
DISPLAY 0.617021 (60 2810);
PAINT ORANGE (60 2810);
FORCEPROP 1 LAST PACK_TYPE PIP
J 0
(-900 3150);
PAINT SKYBLUE (-900 3150);
DISPLAY INVISIBLE (-900 3150);
FORCEPROP 2 LAST BOM_COST MEM
J 0
(-450 2000);
PAINT ORANGE (-450 2000);
DISPLAY INVISIBLE (-450 2000);
FORCEPROP 2 LAST CDS_LIB mstr_sconn
J 0
(-450 2000);
PAINT ORANGE (-450 2000);
DISPLAY INVISIBLE (-450 2000);
FORCEPROP 2 LAST SEC_TYPE PIP
J 0
(-900 3150);
DISPLAY 1.021277 (-900 3150);
PAINT ORANGE (-900 3150);
DISPLAY INVISIBLE (-900 3150);
FORCEPROP 2 LAST SEC 4
J 0
(-900 3150);
DISPLAY 0.680851 (-900 3150);
PAINT MONO (-900 3150);
DISPLAY INVISIBLE (-900 3150);
FORCEPROP 2 LAST CDS_LOCATION J1G2
J 0
(-900 3100);
DISPLAY 0.617021 (-900 3100);
PAINT AQUA (-900 3100);
DISPLAY INVISIBLE (-900 3100);
FORCEPROP 1 LAST PATH I169
J 0
(-450 3050);
PAINT GREEN (-450 3050);
DISPLAY INVISIBLE (-450 3050);
FORCEPROP 2 LAST ROOM DDR4_CH_H
J 0
(-450 2000);
PAINT ORANGE (-450 2000);
DISPLAY INVISIBLE (-450 2000);
FORCEADD TAP..6
R 2
(850 4600);
FORCEPROP 3 LASTPIN (800 4600) SIG_NAME M_H_DQS_DN<12>
J 0
(810 4610);
DISPLAY 0.659574 (810 4610);
PAINT MONO (810 4610);
DISPLAY INVISIBLE (810 4610);
FORCEPROP 1 LASTPIN (800 4600) BN 12
J 2
(850 4610);
DISPLAY 0.617021 (850 4610);
PAINT PINK (850 4610);
FORCEPROP 2 LAST CDS_LIB mstr_standard
J 0
(850 4600);
DISPLAY 0.787234 (850 4600);
PAINT MONO (850 4600);
DISPLAY INVISIBLE (850 4600);
FORCEPROP 1 LAST BODY_TYPE PLUMBING
J 2
(850 4550);
DISPLAY 1.234043 (850 4550);
PAINT GREEN (850 4550);
DISPLAY INVISIBLE (850 4550);
FORCEPROP 1 LAST HDL_TAP TRUE
J 2
(525 4475);
DISPLAY 1.234043 (525 4475);
PAINT GREEN (525 4475);
DISPLAY INVISIBLE (525 4475);
FORCEPROP 1 LAST PATH I17
J 2
(850 4600);
DISPLAY 0.936170 (850 4600);
PAINT GREEN (850 4600);
DISPLAY INVISIBLE (850 4600);
FORCEADD GND..1
R 2
(2450 1100);
FORCEPROP 3 LASTPIN (2450 1150) SIG_NAME GND\g
J 0
(2460 1160);
DISPLAY 0.659574 (2460 1160);
PAINT MONO (2460 1160);
DISPLAY INVISIBLE (2460 1160);
FORCEPROP 1 LAST VOLTAGE 0
J 0
(2450 1100);
PAINT SKYBLUE (2450 1100);
DISPLAY INVISIBLE (2450 1100);
FORCEPROP 2 LAST CDS_LIB mstr_symbols
J 0
(2450 1100);
DISPLAY 0.787234 (2450 1100);
PAINT MONO (2450 1100);
DISPLAY INVISIBLE (2450 1100);
FORCEPROP 1 LAST SIZE 1B
J 2
(2375 1050);
DISPLAY 1.170213 (2375 1050);
PAINT GREEN (2375 1050);
DISPLAY INVISIBLE (2375 1050);
FORCEPROP 2 LAST BOM_COST MEM
J 0
(2450 1105);
PAINT ORANGE (2450 1105);
DISPLAY INVISIBLE (2450 1105);
FORCEPROP 1 LAST BODY_TYPE PLUMBING
J 2
(2495 1057);
DISPLAY 0.340426 (2495 1057);
PAINT GREEN (2495 1057);
DISPLAY INVISIBLE (2495 1057);
FORCEPROP 1 LAST PATH I170
J 2
(2375 1100);
DISPLAY 1.404255 (2375 1100);
PAINT GREEN (2375 1100);
DISPLAY INVISIBLE (2375 1100);
FORCEPROP 2 LAST ROOM DDR4_CH_H
J 0
(2450 1105);
PAINT ORANGE (2450 1105);
DISPLAY INVISIBLE (2450 1105);
FORCEPROP 1 LAST HDL_POWER GND
J 2
(2450 1250);
DISPLAY 0.553191 (2450 1250);
PAINT GREEN (2450 1250);
DISPLAY INVISIBLE (2450 1250);
FORCEADD OFFPAGE..1
(-4000 1850);
FORCEPROP 2 LAST $XR5 82 
J 0
(-4701 1850);
DISPLAY 0.638298 (-4701 1850);
PAINT MONO (-4701 1850);
FORCEPROP 2 LAST $XR4 81 
J 0
(-4611 1850);
DISPLAY 0.638298 (-4611 1850);
PAINT MONO (-4611 1850);
FORCEPROP 2 LAST $XR3 80 
J 0
(-4521 1850);
DISPLAY 0.638298 (-4521 1850);
PAINT MONO (-4521 1850);
FORCEPROP 2 LAST $XR2 78 
J 0
(-4431 1850);
DISPLAY 0.638298 (-4431 1850);
PAINT MONO (-4431 1850);
FORCEPROP 2 LAST $XR1 77 
J 0
(-4341 1850);
DISPLAY 0.638298 (-4341 1850);
PAINT MONO (-4341 1850);
FORCEPROP 2 LAST $XR0 99 
J 0
(-4251 1850);
DISPLAY 0.638298 (-4251 1850);
PAINT MONO (-4251 1850);
FORCEPROP 2 LAST CDS_LIB mstr_standard
J 0
(-4000 1850);
DISPLAY 0.787234 (-4000 1850);
PAINT MONO (-4000 1850);
DISPLAY INVISIBLE (-4000 1850);
FORCEPROP 1 LAST OFFPAGE TRUE
J 0
(-3675 1725);
DISPLAY 0.936170 (-3675 1725);
PAINT GREEN (-3675 1725);
DISPLAY INVISIBLE (-3675 1725);
FORCEPROP 1 LAST COMMENT_BODY TRUE
J 0
(-3875 1750);
DISPLAY 0.936170 (-3875 1750);
PAINT GREEN (-3875 1750);
DISPLAY INVISIBLE (-3875 1750);
FORCEPROP 2 LAST PATH I171
J 0
(-4275 1900);
DISPLAY 0.787234 (-4275 1900);
PAINT ORANGE (-4275 1900);
DISPLAY INVISIBLE (-4275 1900);
FORCEADD OFFPAGE..6
(-4000 1900);
FORCEPROP 2 LASTPIN (-3950 1900) SIG_NAME SMB_DDR_GHJ_VPP_SDA
J 0
(-3910 1910);
DISPLAY 0.617021 (-3910 1910);
PAINT ORANGE (-3910 1910);
FORCEPROP 2 LAST $XR5 99 
J 0
(-4699 1900);
DISPLAY 0.638298 (-4699 1900);
PAINT MONO (-4699 1900);
FORCEPROP 2 LAST $XR4 82 
J 0
(-4609 1900);
DISPLAY 0.638298 (-4609 1900);
PAINT MONO (-4609 1900);
FORCEPROP 2 LAST $XR3 81 
J 0
(-4519 1900);
DISPLAY 0.638298 (-4519 1900);
PAINT MONO (-4519 1900);
FORCEPROP 2 LAST $XR2 80 
J 0
(-4429 1900);
DISPLAY 0.638298 (-4429 1900);
PAINT MONO (-4429 1900);
FORCEPROP 2 LAST $XR1 78 
J 0
(-4339 1900);
DISPLAY 0.638298 (-4339 1900);
PAINT MONO (-4339 1900);
FORCEPROP 2 LAST $XR0 77 
J 0
(-4249 1900);
DISPLAY 0.638298 (-4249 1900);
PAINT MONO (-4249 1900);
FORCEPROP 2 LAST CDS_LIB mstr_standard
J 0
(-4000 1900);
DISPLAY 0.787234 (-4000 1900);
PAINT MONO (-4000 1900);
DISPLAY INVISIBLE (-4000 1900);
FORCEPROP 1 LAST OFFPAGE TRUE
J 0
(-3675 1775);
DISPLAY 0.936170 (-3675 1775);
PAINT GREEN (-3675 1775);
DISPLAY INVISIBLE (-3675 1775);
FORCEPROP 1 LAST COMMENT_BODY TRUE
J 0
(-3900 1825);
DISPLAY 0.936170 (-3900 1825);
PAINT GREEN (-3900 1825);
DISPLAY INVISIBLE (-3900 1825);
FORCEPROP 2 LAST PATH I172
J 0
(-4325 1950);
DISPLAY 0.787234 (-4325 1950);
PAINT ORANGE (-4325 1950);
DISPLAY INVISIBLE (-4325 1950);
FORCEADD OFFPAGE..1
(-4700 1750);
FORCEPROP 2 LAST $XR1 80 
J 0
(-5042 1750);
DISPLAY 0.638298 (-5042 1750);
PAINT MONO (-5042 1750);
FORCEPROP 2 LAST $XR0 100 
J 0
(-4952 1750);
DISPLAY 0.638298 (-4952 1750);
PAINT MONO (-4952 1750);
FORCEPROP 2 LAST CDS_LIB mstr_standard
J 0
(-4700 1750);
DISPLAY 0.787234 (-4700 1750);
PAINT MONO (-4700 1750);
DISPLAY INVISIBLE (-4700 1750);
FORCEPROP 1 LAST OFFPAGE TRUE
J 0
(-4375 1625);
DISPLAY 0.936170 (-4375 1625);
PAINT GREEN (-4375 1625);
DISPLAY INVISIBLE (-4375 1625);
FORCEPROP 1 LAST COMMENT_BODY TRUE
J 0
(-4575 1650);
DISPLAY 0.936170 (-4575 1650);
PAINT GREEN (-4575 1650);
DISPLAY INVISIBLE (-4575 1650);
FORCEPROP 2 LAST PATH I173
J 0
(-4950 1800);
DISPLAY 0.787234 (-4950 1800);
PAINT ORANGE (-4950 1800);
DISPLAY INVISIBLE (-4950 1800);
FORCEADD GND..1
R 2
(-5200 1900);
FORCEPROP 3 LASTPIN (-5200 1950) SIG_NAME GND\g
J 0
(-5190 1960);
DISPLAY 0.659574 (-5190 1960);
PAINT MONO (-5190 1960);
DISPLAY INVISIBLE (-5190 1960);
FORCEPROP 1 LAST VOLTAGE 0
J 0
(-5200 1900);
PAINT SKYBLUE (-5200 1900);
DISPLAY INVISIBLE (-5200 1900);
FORCEPROP 2 LAST CDS_LIB mstr_symbols
J 0
(-5200 1900);
DISPLAY 0.787234 (-5200 1900);
PAINT MONO (-5200 1900);
DISPLAY INVISIBLE (-5200 1900);
FORCEPROP 1 LAST SIZE 1B
J 2
(-5275 1850);
DISPLAY 1.170213 (-5275 1850);
PAINT GREEN (-5275 1850);
DISPLAY INVISIBLE (-5275 1850);
FORCEPROP 2 LAST BOM_COST MEM
J 0
(-5200 1905);
PAINT ORANGE (-5200 1905);
DISPLAY INVISIBLE (-5200 1905);
FORCEPROP 1 LAST BODY_TYPE PLUMBING
J 2
(-5155 1857);
DISPLAY 0.340426 (-5155 1857);
PAINT GREEN (-5155 1857);
DISPLAY INVISIBLE (-5155 1857);
FORCEPROP 1 LAST PATH I175
J 2
(-5275 1900);
DISPLAY 1.404255 (-5275 1900);
PAINT GREEN (-5275 1900);
DISPLAY INVISIBLE (-5275 1900);
FORCEPROP 2 LAST ROOM DDR4_CH_H
J 0
(-5200 1905);
PAINT ORANGE (-5200 1905);
DISPLAY INVISIBLE (-5200 1905);
FORCEPROP 1 LAST HDL_POWER GND
J 2
(-5200 2050);
DISPLAY 0.553191 (-5200 2050);
PAINT GREEN (-5200 2050);
DISPLAY INVISIBLE (-5200 2050);
FORCEADD OFFPAGE..5
(-4325 2600);
FORCEPROP 2 LAST $XR23 94 
J 0
(-5029 2636);
DISPLAY 0.638298 (-5029 2636);
PAINT MONO (-5029 2636);
FORCEPROP 2 LAST $XR22 88 
J 0
(-4939 2636);
DISPLAY 0.638298 (-4939 2636);
PAINT MONO (-4939 2636);
FORCEPROP 2 LAST $XR21 87 
J 0
(-4849 2636);
DISPLAY 0.638298 (-4849 2636);
PAINT MONO (-4849 2636);
FORCEPROP 2 LAST $XR20 86 
J 0
(-4759 2636);
DISPLAY 0.638298 (-4759 2636);
PAINT MONO (-4759 2636);
FORCEPROP 2 LAST $XR19 85 
J 0
(-4669 2636);
DISPLAY 0.638298 (-4669 2636);
PAINT MONO (-4669 2636);
FORCEPROP 2 LAST $XR18 84 
J 0
(-4579 2636);
DISPLAY 0.638298 (-4579 2636);
PAINT MONO (-4579 2636);
FORCEPROP 2 LAST $XR17 83 
J 0
(-5299 2564);
DISPLAY 0.638298 (-5299 2564);
PAINT MONO (-5299 2564);
FORCEPROP 2 LAST $XR16 82 
J 0
(-5209 2564);
DISPLAY 0.638298 (-5209 2564);
PAINT MONO (-5209 2564);
FORCEPROP 2 LAST $XR15 81 
J 0
(-5119 2564);
DISPLAY 0.638298 (-5119 2564);
PAINT MONO (-5119 2564);
FORCEPROP 2 LAST $XR14 80 
J 0
(-5029 2564);
DISPLAY 0.638298 (-5029 2564);
PAINT MONO (-5029 2564);
FORCEPROP 2 LAST $XR13 78 
J 0
(-4939 2564);
DISPLAY 0.638298 (-4939 2564);
PAINT MONO (-4939 2564);
FORCEPROP 2 LAST $XR12 77 
J 0
(-4849 2564);
DISPLAY 0.638298 (-4849 2564);
PAINT MONO (-4849 2564);
FORCEPROP 2 LAST $XR11 54 
J 0
(-4759 2564);
DISPLAY 0.638298 (-4759 2564);
PAINT MONO (-4759 2564);
FORCEPROP 2 LAST $XR10 53 
J 0
(-4669 2564);
DISPLAY 0.638298 (-4669 2564);
PAINT MONO (-4669 2564);
FORCEPROP 2 LAST $XR9 52 
J 0
(-4579 2564);
DISPLAY 0.638298 (-4579 2564);
PAINT MONO (-4579 2564);
FORCEPROP 2 LAST $XR8 51 
J 0
(-5299 2600);
DISPLAY 0.638298 (-5299 2600);
PAINT MONO (-5299 2600);
FORCEPROP 2 LAST $XR7 50 
J 0
(-5209 2600);
DISPLAY 0.638298 (-5209 2600);
PAINT MONO (-5209 2600);
FORCEPROP 2 LAST $XR6 49 
J 0
(-5119 2600);
DISPLAY 0.638298 (-5119 2600);
PAINT MONO (-5119 2600);
FORCEPROP 2 LAST $XR5 48 
J 0
(-5029 2600);
DISPLAY 0.638298 (-5029 2600);
PAINT MONO (-5029 2600);
FORCEPROP 2 LAST $XR4 47 
J 0
(-4939 2600);
DISPLAY 0.638298 (-4939 2600);
PAINT MONO (-4939 2600);
FORCEPROP 2 LAST $XR3 46 
J 0
(-4849 2600);
DISPLAY 0.638298 (-4849 2600);
PAINT MONO (-4849 2600);
FORCEPROP 2 LAST $XR2 45 
J 0
(-4759 2600);
DISPLAY 0.638298 (-4759 2600);
PAINT MONO (-4759 2600);
FORCEPROP 2 LAST $XR1 44 
J 0
(-4669 2600);
DISPLAY 0.638298 (-4669 2600);
PAINT MONO (-4669 2600);
FORCEPROP 2 LAST $XR0 43 
J 0
(-4579 2600);
DISPLAY 0.638298 (-4579 2600);
PAINT MONO (-4579 2600);
FORCEPROP 2 LAST CDS_LIB mstr_standard
J 0
(-4325 2600);
DISPLAY 0.787234 (-4325 2600);
PAINT MONO (-4325 2600);
DISPLAY INVISIBLE (-4325 2600);
FORCEPROP 1 LAST OFFPAGE TRUE
J 0
(-4000 2475);
DISPLAY 1.404255 (-4000 2475);
PAINT GREEN (-4000 2475);
DISPLAY INVISIBLE (-4000 2475);
FORCEPROP 1 LAST COMMENT_BODY TRUE
J 0
(-4225 2525);
DISPLAY 1.404255 (-4225 2525);
PAINT GREEN (-4225 2525);
DISPLAY INVISIBLE (-4225 2525);
FORCEPROP 2 LAST PATH I176
J 0
(-4275 2675);
DISPLAY 0.787234 (-4275 2675);
PAINT ORANGE (-4275 2675);
DISPLAY INVISIBLE (-4275 2675);
FORCEADD GND..1
(-4600 1300);
FORCEPROP 3 LASTPIN (-4600 1350) SIG_NAME GND\g
J 0
(-4590 1360);
DISPLAY 0.659574 (-4590 1360);
PAINT MONO (-4590 1360);
DISPLAY INVISIBLE (-4590 1360);
FORCEPROP 1 LAST VOLTAGE 0
J 0
(-4600 1300);
PAINT SKYBLUE (-4600 1300);
DISPLAY INVISIBLE (-4600 1300);
FORCEPROP 2 LAST BOM_COST MEM
J 0
(-4600 1305);
PAINT ORANGE (-4600 1305);
DISPLAY INVISIBLE (-4600 1305);
FORCEPROP 1 LAST SIZE 1B
J 0
(-4525 1250);
DISPLAY 1.787234 (-4525 1250);
PAINT GREEN (-4525 1250);
DISPLAY INVISIBLE (-4525 1250);
FORCEPROP 2 LAST CDS_LIB mstr_symbols
J 0
(-4600 1300);
PAINT ORANGE (-4600 1300);
DISPLAY INVISIBLE (-4600 1300);
FORCEPROP 1 LAST BODY_TYPE PLUMBING
J 0
(-4645 1257);
DISPLAY 0.340426 (-4645 1257);
PAINT GREEN (-4645 1257);
DISPLAY INVISIBLE (-4645 1257);
FORCEPROP 1 LAST PATH I177
J 0
(-4525 1300);
DISPLAY 1.404255 (-4525 1300);
PAINT GREEN (-4525 1300);
DISPLAY INVISIBLE (-4525 1300);
FORCEPROP 2 LAST ROOM DDR4_CH_H
J 0
(-4600 1305);
PAINT ORANGE (-4600 1305);
DISPLAY INVISIBLE (-4600 1305);
FORCEPROP 1 LAST HDL_POWER GND
J 0
(-4600 1450);
DISPLAY 1.404255 (-4600 1450);
PAINT GREEN (-4600 1450);
DISPLAY INVISIBLE (-4600 1450);
FORCEADD CAP_A..1
R 2
(-4600 1550);
FORCEPROP 1 LAST LOCATION C9U7
J 2
(-4650 1650);
DISPLAY 0.617021 (-4650 1650);
PAINT AQUA (-4650 1650);
FORCEPROP 1 LAST PART_NUMBER A36096-045
J 2
(-4650 1400);
DISPLAY 0.617021 (-4650 1400);
PAINT BLUE (-4650 1400);
FORCEPROP 1 LAST VALUE 0.01UF
J 2
(-4650 1600);
DISPLAY 0.617021 (-4650 1600);
PAINT SKYBLUE (-4650 1600);
FORCEPROP 1 LAST TOLERANCE 10%
J 2
(-4650 1500);
DISPLAY 0.617021 (-4650 1500);
PAINT SKYBLUE (-4650 1500);
FORCEPROP 1 LAST PACK_TYPE 0402V
J 2
(-4650 1350);
DISPLAY 0.617021 (-4650 1350);
PAINT SKYBLUE (-4650 1350);
FORCEPROP 1 LAST VOLTAGE 25V
J 2
(-4650 1550);
DISPLAY 0.617021 (-4650 1550);
PAINT SKYBLUE (-4650 1550);
FORCEPROP 1 LAST MATERIAL X7R
J 2
(-4650 1450);
DISPLAY 0.617021 (-4650 1450);
PAINT SKYBLUE (-4650 1450);
FORCEPROP 2 LAST CDS_LOCATION C9U7
J 2
(-4650 1650);
DISPLAY 0.617021 (-4650 1650);
PAINT AQUA (-4650 1650);
DISPLAY INVISIBLE (-4650 1650);
FORCEPROP 2 LAST BOM_COST MEM
J 0
(-4600 1550);
PAINT ORANGE (-4600 1550);
DISPLAY INVISIBLE (-4600 1550);
FORCEPROP 2 LAST CDS_LIB dev_discrete
J 0
(-4600 1550);
PAINT ORANGE (-4600 1550);
DISPLAY INVISIBLE (-4600 1550);
FORCEPROP 2 LAST CDS_SEC 1
J 2
(-4650 1750);
PAINT MONO (-4650 1750);
DISPLAY INVISIBLE (-4650 1750);
FORCEPROP 2 LAST $SEC 1
J 0
(-4650 1750);
PAINT MONO (-4650 1750);
DISPLAY INVISIBLE (-4650 1750);
FORCEPROP 1 LAST PATH I178
J 2
(-4650 1700);
DISPLAY 0.978723 (-4650 1700);
PAINT WHITE (-4650 1700);
DISPLAY INVISIBLE (-4650 1700);
FORCEPROP 2 LAST ROOM DDR4_CH_J
J 0
(-4600 1550);
PAINT ORANGE (-4600 1550);
DISPLAY INVISIBLE (-4600 1550);
FORCEPROP 1 LASTPIN (-4600 1650) $PN 1
J 2
(-4610 1630);
DISPLAY 0.787234 (-4610 1630);
PAINT ORANGE (-4610 1630);
DISPLAY INVISIBLE (-4610 1630);
FORCEPROP 1 LASTPIN (-4600 1450) $PN 2
J 2
(-4610 1430);
DISPLAY 0.787234 (-4610 1430);
PAINT ORANGE (-4610 1430);
DISPLAY INVISIBLE (-4610 1430);
FORCEADD PVPP_GHJ..1
(-1150 3000);
FORCEPROP 3 LASTPIN (-1150 2950) SIG_NAME PVPP_GHJ\g
J 0
(-1140 2960);
DISPLAY 0.659574 (-1140 2960);
PAINT MONO (-1140 2960);
DISPLAY INVISIBLE (-1140 2960);
FORCEPROP 1 LAST VOLTAGE 2.5V
J 0
(-1195 2957);
DISPLAY 0.340426 (-1195 2957);
PAINT SKYBLUE (-1195 2957);
DISPLAY INVISIBLE (-1195 2957);
FORCEPROP 0 LAST BOM_COST MEM
J 0
(-1150 3100);
PAINT ORANGE (-1150 3100);
DISPLAY INVISIBLE (-1150 3100);
FORCEPROP 2 LAST CDS_LIB mstr_symbols
J 0
(-1150 3000);
PAINT ORANGE (-1150 3000);
DISPLAY INVISIBLE (-1150 3000);
FORCEPROP 1 LAST BODY_TYPE PLUMBING
J 0
(-1195 2957);
DISPLAY 0.340426 (-1195 2957);
PAINT GREEN (-1195 2957);
DISPLAY INVISIBLE (-1195 2957);
FORCEPROP 1 LAST PATH I179
J 0
(-1100 3025);
DISPLAY 0.872340 (-1100 3025);
PAINT AQUA (-1100 3025);
DISPLAY INVISIBLE (-1100 3025);
FORCEPROP 2 LAST ROOM DDR4_CH_H
J 0
(-1150 3100);
PAINT ORANGE (-1150 3100);
DISPLAY INVISIBLE (-1150 3100);
FORCEPROP 1 LAST HDL_POWER PVPP_GHJ
J 1
(-1150 3050);
DISPLAY 0.872340 (-1150 3050);
PAINT GREEN (-1150 3050);
DISPLAY INVISIBLE (-1150 3050);
FORCEADD TAP..6
R 2
(850 4500);
FORCEPROP 3 LASTPIN (800 4500) SIG_NAME M_H_DQS_DN<11>
J 0
(810 4510);
DISPLAY 0.659574 (810 4510);
PAINT MONO (810 4510);
DISPLAY INVISIBLE (810 4510);
FORCEPROP 1 LASTPIN (800 4500) BN 11
J 2
(850 4510);
DISPLAY 0.617021 (850 4510);
PAINT PINK (850 4510);
FORCEPROP 2 LAST CDS_LIB mstr_standard
J 0
(850 4500);
DISPLAY 0.787234 (850 4500);
PAINT MONO (850 4500);
DISPLAY INVISIBLE (850 4500);
FORCEPROP 1 LAST BODY_TYPE PLUMBING
J 2
(850 4450);
DISPLAY 1.234043 (850 4450);
PAINT GREEN (850 4450);
DISPLAY INVISIBLE (850 4450);
FORCEPROP 1 LAST HDL_TAP TRUE
J 2
(525 4375);
DISPLAY 1.234043 (525 4375);
PAINT GREEN (525 4375);
DISPLAY INVISIBLE (525 4375);
FORCEPROP 1 LAST PATH I18
J 2
(850 4500);
DISPLAY 0.936170 (850 4500);
PAINT GREEN (850 4500);
DISPLAY INVISIBLE (850 4500);
FORCEADD PVPP_GHJ..1
(-5200 2250);
FORCEPROP 3 LASTPIN (-5200 2200) SIG_NAME PVPP_GHJ\g
J 0
(-5190 2210);
DISPLAY 0.659574 (-5190 2210);
PAINT MONO (-5190 2210);
DISPLAY INVISIBLE (-5190 2210);
FORCEPROP 1 LAST VOLTAGE 2.5V
J 0
(-5245 2207);
DISPLAY 0.340426 (-5245 2207);
PAINT SKYBLUE (-5245 2207);
DISPLAY INVISIBLE (-5245 2207);
FORCEPROP 0 LAST BOM_COST MEM
J 0
(-5200 2350);
PAINT ORANGE (-5200 2350);
DISPLAY INVISIBLE (-5200 2350);
FORCEPROP 2 LAST CDS_LIB mstr_symbols
J 0
(-5200 2250);
PAINT ORANGE (-5200 2250);
DISPLAY INVISIBLE (-5200 2250);
FORCEPROP 1 LAST BODY_TYPE PLUMBING
J 0
(-5245 2207);
DISPLAY 0.340426 (-5245 2207);
PAINT GREEN (-5245 2207);
DISPLAY INVISIBLE (-5245 2207);
FORCEPROP 1 LAST PATH I180
J 0
(-5150 2275);
DISPLAY 0.872340 (-5150 2275);
PAINT AQUA (-5150 2275);
DISPLAY INVISIBLE (-5150 2275);
FORCEPROP 2 LAST ROOM DDR4_CH_H
J 0
(-5200 2350);
PAINT ORANGE (-5200 2350);
DISPLAY INVISIBLE (-5200 2350);
FORCEPROP 1 LAST HDL_POWER PVPP_GHJ
J 1
(-5200 2300);
DISPLAY 0.872340 (-5200 2300);
PAINT GREEN (-5200 2300);
DISPLAY INVISIBLE (-5200 2300);
FORCEADD OFFPAGE..1
(-4000 1450);
FORCEPROP 2 LAST $XR5 82 
J 0
(-4341 1414);
DISPLAY 0.638298 (-4341 1414);
PAINT MONO (-4341 1414);
FORCEPROP 2 LAST $XR4 81 
J 0
(-4251 1414);
DISPLAY 0.638298 (-4251 1414);
PAINT MONO (-4251 1414);
FORCEPROP 2 LAST $XR3 80 
J 0
(-4521 1450);
DISPLAY 0.638298 (-4521 1450);
PAINT MONO (-4521 1450);
FORCEPROP 2 LAST $XR2 78 
J 0
(-4431 1450);
DISPLAY 0.638298 (-4431 1450);
PAINT MONO (-4431 1450);
FORCEPROP 2 LAST $XR1 77 
J 0
(-4341 1450);
DISPLAY 0.638298 (-4341 1450);
PAINT MONO (-4341 1450);
FORCEPROP 2 LAST $XR0 89 
J 0
(-4251 1450);
DISPLAY 0.638298 (-4251 1450);
PAINT MONO (-4251 1450);
FORCEPROP 2 LAST CDS_LIB mstr_standard
J 0
(-4000 1450);
PAINT ORANGE (-4000 1450);
DISPLAY INVISIBLE (-4000 1450);
FORCEPROP 1 LAST OFFPAGE TRUE
J 0
(-3675 1325);
DISPLAY 0.936170 (-3675 1325);
PAINT GREEN (-3675 1325);
DISPLAY INVISIBLE (-3675 1325);
FORCEPROP 1 LAST COMMENT_BODY TRUE
J 0
(-3875 1350);
DISPLAY 0.936170 (-3875 1350);
PAINT GREEN (-3875 1350);
DISPLAY INVISIBLE (-3875 1350);
FORCEPROP 2 LAST PATH I181
J 0
(-3950 1525);
PAINT ORANGE (-3950 1525);
DISPLAY INVISIBLE (-3950 1525);
FORCEADD TAP..6
R 2
(650 3450);
FORCEPROP 3 LASTPIN (600 3450) SIG_NAME M_H_DQS_DP<0>
J 0
(610 3460);
DISPLAY 0.659574 (610 3460);
PAINT MONO (610 3460);
DISPLAY INVISIBLE (610 3460);
FORCEPROP 1 LASTPIN (600 3450) BN 0
J 2
(650 3460);
DISPLAY 0.617021 (650 3460);
PAINT PINK (650 3460);
FORCEPROP 2 LAST CDS_LIB mstr_standard
J 0
(650 3450);
DISPLAY 0.787234 (650 3450);
PAINT MONO (650 3450);
DISPLAY INVISIBLE (650 3450);
FORCEPROP 1 LAST BODY_TYPE PLUMBING
J 2
(650 3400);
DISPLAY 1.234043 (650 3400);
PAINT GREEN (650 3400);
DISPLAY INVISIBLE (650 3400);
FORCEPROP 1 LAST HDL_TAP TRUE
J 2
(325 3325);
DISPLAY 1.234043 (325 3325);
PAINT GREEN (325 3325);
DISPLAY INVISIBLE (325 3325);
FORCEPROP 1 LAST PATH I185
J 2
(652 3450);
DISPLAY 0.872340 (652 3450);
PAINT GREEN (652 3450);
DISPLAY INVISIBLE (652 3450);
FORCEADD P12V_NVDIMM_GHJ..1
(250 2975);
FORCEPROP 3 LASTPIN (250 2925) SIG_NAME P12V_NVDIMM_GHJ\g
J 0
(260 2935);
DISPLAY 0.659574 (260 2935);
PAINT MONO (260 2935);
DISPLAY INVISIBLE (260 2935);
FORCEPROP 1 LAST VOLTAGE 12.0
J 0
(205 2932);
DISPLAY 0.340426 (205 2932);
PAINT SKYBLUE (205 2932);
DISPLAY INVISIBLE (205 2932);
FORCEPROP 2 LAST CDS_LIB mstr_symbols
J 0
(250 2975);
PAINT ORANGE (250 2975);
DISPLAY INVISIBLE (250 2975);
FORCEPROP 1 LAST BODY_TYPE PLUMBING
J 0
(205 2932);
DISPLAY 0.340426 (205 2932);
PAINT GREEN (205 2932);
DISPLAY INVISIBLE (205 2932);
FORCEPROP 1 LAST PATH I186
J 0
(300 3000);
DISPLAY 0.872340 (300 3000);
PAINT AQUA (300 3000);
DISPLAY INVISIBLE (300 3000);
FORCEPROP 1 LAST HDL_POWER P12V_NVDIMM_GHJ
J 1
(250 3025);
DISPLAY 0.872340 (250 3025);
PAINT GREEN (250 3025);
DISPLAY INVISIBLE (250 3025);
FORCEADD TAP..6
R 2
(850 4400);
FORCEPROP 3 LASTPIN (800 4400) SIG_NAME M_H_DQS_DN<10>
J 0
(810 4410);
DISPLAY 0.659574 (810 4410);
PAINT MONO (810 4410);
DISPLAY INVISIBLE (810 4410);
FORCEPROP 1 LASTPIN (800 4400) BN 10
J 2
(850 4410);
DISPLAY 0.617021 (850 4410);
PAINT PINK (850 4410);
FORCEPROP 2 LAST CDS_LIB mstr_standard
J 0
(850 4400);
DISPLAY 0.787234 (850 4400);
PAINT MONO (850 4400);
DISPLAY INVISIBLE (850 4400);
FORCEPROP 1 LAST BODY_TYPE PLUMBING
J 2
(850 4350);
DISPLAY 1.234043 (850 4350);
PAINT GREEN (850 4350);
DISPLAY INVISIBLE (850 4350);
FORCEPROP 1 LAST HDL_TAP TRUE
J 2
(525 4275);
DISPLAY 1.234043 (525 4275);
PAINT GREEN (525 4275);
DISPLAY INVISIBLE (525 4275);
FORCEPROP 1 LAST PATH I19
J 2
(850 4400);
DISPLAY 0.936170 (850 4400);
PAINT GREEN (850 4400);
DISPLAY INVISIBLE (850 4400);
FORCEADD OFFPAGE..3
(1550 5200);
FORCEPROP 2 LAST $XR1 80 
J 0
(1854 5200);
DISPLAY 0.638298 (1854 5200);
PAINT MONO (1854 5200);
FORCEPROP 2 LAST $XR0 58 
J 0
(1764 5200);
DISPLAY 0.638298 (1764 5200);
PAINT MONO (1764 5200);
FORCEPROP 2 LAST CDS_LIB mstr_standard
J 0
(1550 5200);
DISPLAY 0.787234 (1550 5200);
PAINT MONO (1550 5200);
DISPLAY INVISIBLE (1550 5200);
FORCEPROP 1 LAST OFFPAGE TRUE
J 0
(1875 5075);
DISPLAY 0.936170 (1875 5075);
PAINT GREEN (1875 5075);
DISPLAY INVISIBLE (1875 5075);
FORCEPROP 1 LAST COMMENT_BODY TRUE
J 0
(1500 5100);
DISPLAY 0.936170 (1500 5100);
PAINT GREEN (1500 5100);
DISPLAY INVISIBLE (1500 5100);
FORCEPROP 2 LAST PATH I2
J 0
(1750 5275);
DISPLAY 0.787234 (1750 5275);
PAINT MONO (1750 5275);
DISPLAY INVISIBLE (1750 5275);
FORCEADD TAP..6
R 2
(850 4200);
FORCEPROP 3 LASTPIN (800 4200) SIG_NAME M_H_DQS_DN<8>
J 0
(810 4210);
DISPLAY 0.659574 (810 4210);
PAINT MONO (810 4210);
DISPLAY INVISIBLE (810 4210);
FORCEPROP 1 LASTPIN (800 4200) BN 8
J 2
(850 4210);
DISPLAY 0.617021 (850 4210);
PAINT PINK (850 4210);
FORCEPROP 2 LAST CDS_LIB mstr_standard
J 0
(850 4200);
DISPLAY 0.787234 (850 4200);
PAINT MONO (850 4200);
DISPLAY INVISIBLE (850 4200);
FORCEPROP 1 LAST BODY_TYPE PLUMBING
J 2
(850 4150);
DISPLAY 1.234043 (850 4150);
PAINT GREEN (850 4150);
DISPLAY INVISIBLE (850 4150);
FORCEPROP 1 LAST HDL_TAP TRUE
J 2
(525 4075);
DISPLAY 1.234043 (525 4075);
PAINT GREEN (525 4075);
DISPLAY INVISIBLE (525 4075);
FORCEPROP 1 LAST PATH I20
J 2
(850 4200);
DISPLAY 0.936170 (850 4200);
PAINT GREEN (850 4200);
DISPLAY INVISIBLE (850 4200);
FORCEADD TAP..6
R 2
(850 4300);
FORCEPROP 3 LASTPIN (800 4300) SIG_NAME M_H_DQS_DN<9>
J 0
(810 4310);
DISPLAY 0.659574 (810 4310);
PAINT MONO (810 4310);
DISPLAY INVISIBLE (810 4310);
FORCEPROP 1 LASTPIN (800 4300) BN 9
J 2
(850 4310);
DISPLAY 0.617021 (850 4310);
PAINT PINK (850 4310);
FORCEPROP 2 LAST CDS_LIB mstr_standard
J 0
(850 4300);
DISPLAY 0.787234 (850 4300);
PAINT MONO (850 4300);
DISPLAY INVISIBLE (850 4300);
FORCEPROP 1 LAST BODY_TYPE PLUMBING
J 2
(850 4250);
DISPLAY 1.234043 (850 4250);
PAINT GREEN (850 4250);
DISPLAY INVISIBLE (850 4250);
FORCEPROP 1 LAST HDL_TAP TRUE
J 2
(525 4175);
DISPLAY 1.234043 (525 4175);
PAINT GREEN (525 4175);
DISPLAY INVISIBLE (525 4175);
FORCEPROP 1 LAST PATH I21
J 2
(850 4300);
DISPLAY 0.936170 (850 4300);
PAINT GREEN (850 4300);
DISPLAY INVISIBLE (850 4300);
FORCEADD TAP..6
R 2
(650 4550);
FORCEPROP 3 LASTPIN (600 4550) SIG_NAME M_H_DQS_DP<11>
J 0
(610 4560);
DISPLAY 0.659574 (610 4560);
PAINT MONO (610 4560);
DISPLAY INVISIBLE (610 4560);
FORCEPROP 1 LASTPIN (600 4550) BN 11
J 2
(650 4560);
DISPLAY 0.617021 (650 4560);
PAINT PINK (650 4560);
FORCEPROP 2 LAST CDS_LIB mstr_standard
J 0
(650 4550);
DISPLAY 0.787234 (650 4550);
PAINT MONO (650 4550);
DISPLAY INVISIBLE (650 4550);
FORCEPROP 1 LAST BODY_TYPE PLUMBING
J 2
(650 4500);
DISPLAY 1.234043 (650 4500);
PAINT GREEN (650 4500);
DISPLAY INVISIBLE (650 4500);
FORCEPROP 1 LAST HDL_TAP TRUE
J 2
(325 4425);
DISPLAY 1.234043 (325 4425);
PAINT GREEN (325 4425);
DISPLAY INVISIBLE (325 4425);
FORCEPROP 1 LAST PATH I22
J 2
(650 4550);
DISPLAY 0.936170 (650 4550);
PAINT GREEN (650 4550);
DISPLAY INVISIBLE (650 4550);
FORCEADD TAP..6
R 2
(650 4450);
FORCEPROP 3 LASTPIN (600 4450) SIG_NAME M_H_DQS_DP<10>
J 0
(610 4460);
DISPLAY 0.659574 (610 4460);
PAINT MONO (610 4460);
DISPLAY INVISIBLE (610 4460);
FORCEPROP 1 LASTPIN (600 4450) BN 10
J 2
(650 4460);
DISPLAY 0.617021 (650 4460);
PAINT PINK (650 4460);
FORCEPROP 2 LAST CDS_LIB mstr_standard
J 0
(650 4450);
DISPLAY 0.787234 (650 4450);
PAINT MONO (650 4450);
DISPLAY INVISIBLE (650 4450);
FORCEPROP 1 LAST BODY_TYPE PLUMBING
J 2
(650 4400);
DISPLAY 1.234043 (650 4400);
PAINT GREEN (650 4400);
DISPLAY INVISIBLE (650 4400);
FORCEPROP 1 LAST HDL_TAP TRUE
J 2
(325 4325);
DISPLAY 1.234043 (325 4325);
PAINT GREEN (325 4325);
DISPLAY INVISIBLE (325 4325);
FORCEPROP 1 LAST PATH I23
J 2
(650 4450);
DISPLAY 0.936170 (650 4450);
PAINT GREEN (650 4450);
DISPLAY INVISIBLE (650 4450);
FORCEADD TAP..6
R 2
(650 4350);
FORCEPROP 3 LASTPIN (600 4350) SIG_NAME M_H_DQS_DP<9>
J 0
(610 4360);
DISPLAY 0.659574 (610 4360);
PAINT MONO (610 4360);
DISPLAY INVISIBLE (610 4360);
FORCEPROP 1 LASTPIN (600 4350) BN 9
J 2
(650 4360);
DISPLAY 0.617021 (650 4360);
PAINT PINK (650 4360);
FORCEPROP 2 LAST CDS_LIB mstr_standard
J 0
(650 4350);
DISPLAY 0.787234 (650 4350);
PAINT MONO (650 4350);
DISPLAY INVISIBLE (650 4350);
FORCEPROP 1 LAST BODY_TYPE PLUMBING
J 2
(650 4300);
DISPLAY 1.234043 (650 4300);
PAINT GREEN (650 4300);
DISPLAY INVISIBLE (650 4300);
FORCEPROP 1 LAST HDL_TAP TRUE
J 2
(325 4225);
DISPLAY 1.234043 (325 4225);
PAINT GREEN (325 4225);
DISPLAY INVISIBLE (325 4225);
FORCEPROP 1 LAST PATH I24
J 2
(650 4350);
DISPLAY 0.936170 (650 4350);
PAINT GREEN (650 4350);
DISPLAY INVISIBLE (650 4350);
FORCEADD TAP..6
R 2
(650 4250);
FORCEPROP 3 LASTPIN (600 4250) SIG_NAME M_H_DQS_DP<8>
J 0
(610 4260);
DISPLAY 0.659574 (610 4260);
PAINT MONO (610 4260);
DISPLAY INVISIBLE (610 4260);
FORCEPROP 1 LASTPIN (600 4250) BN 8
J 2
(650 4260);
DISPLAY 0.617021 (650 4260);
PAINT PINK (650 4260);
FORCEPROP 2 LAST CDS_LIB mstr_standard
J 0
(650 4250);
DISPLAY 0.787234 (650 4250);
PAINT MONO (650 4250);
DISPLAY INVISIBLE (650 4250);
FORCEPROP 1 LAST BODY_TYPE PLUMBING
J 2
(650 4200);
DISPLAY 1.234043 (650 4200);
PAINT GREEN (650 4200);
DISPLAY INVISIBLE (650 4200);
FORCEPROP 1 LAST HDL_TAP TRUE
J 2
(325 4125);
DISPLAY 1.234043 (325 4125);
PAINT GREEN (325 4125);
DISPLAY INVISIBLE (325 4125);
FORCEPROP 1 LAST PATH I25
J 2
(650 4250);
DISPLAY 0.936170 (650 4250);
PAINT GREEN (650 4250);
DISPLAY INVISIBLE (650 4250);
FORCEADD TAP..6
R 2
(650 4150);
FORCEPROP 3 LASTPIN (600 4150) SIG_NAME M_H_DQS_DP<7>
J 0
(610 4160);
DISPLAY 0.659574 (610 4160);
PAINT MONO (610 4160);
DISPLAY INVISIBLE (610 4160);
FORCEPROP 1 LASTPIN (600 4150) BN 7
J 2
(650 4160);
DISPLAY 0.617021 (650 4160);
PAINT PINK (650 4160);
FORCEPROP 2 LAST CDS_LIB mstr_standard
J 0
(650 4150);
DISPLAY 0.787234 (650 4150);
PAINT MONO (650 4150);
DISPLAY INVISIBLE (650 4150);
FORCEPROP 1 LAST BODY_TYPE PLUMBING
J 2
(650 4100);
DISPLAY 1.234043 (650 4100);
PAINT GREEN (650 4100);
DISPLAY INVISIBLE (650 4100);
FORCEPROP 1 LAST HDL_TAP TRUE
J 2
(325 4025);
DISPLAY 1.234043 (325 4025);
PAINT GREEN (325 4025);
DISPLAY INVISIBLE (325 4025);
FORCEPROP 1 LAST PATH I26
J 2
(650 4150);
DISPLAY 0.936170 (650 4150);
PAINT GREEN (650 4150);
DISPLAY INVISIBLE (650 4150);
FORCEADD TAP..6
R 2
(850 4100);
FORCEPROP 3 LASTPIN (800 4100) SIG_NAME M_H_DQS_DN<7>
J 0
(810 4110);
DISPLAY 0.659574 (810 4110);
PAINT MONO (810 4110);
DISPLAY INVISIBLE (810 4110);
FORCEPROP 1 LASTPIN (800 4100) BN 7
J 2
(850 4110);
DISPLAY 0.617021 (850 4110);
PAINT PINK (850 4110);
FORCEPROP 2 LAST CDS_LIB mstr_standard
J 0
(850 4100);
DISPLAY 0.787234 (850 4100);
PAINT MONO (850 4100);
DISPLAY INVISIBLE (850 4100);
FORCEPROP 1 LAST BODY_TYPE PLUMBING
J 2
(850 4050);
DISPLAY 1.234043 (850 4050);
PAINT GREEN (850 4050);
DISPLAY INVISIBLE (850 4050);
FORCEPROP 1 LAST HDL_TAP TRUE
J 2
(525 3975);
DISPLAY 1.234043 (525 3975);
PAINT GREEN (525 3975);
DISPLAY INVISIBLE (525 3975);
FORCEPROP 1 LAST PATH I27
J 2
(850 4100);
DISPLAY 0.936170 (850 4100);
PAINT GREEN (850 4100);
DISPLAY INVISIBLE (850 4100);
FORCEADD TAP..6
R 2
(850 4000);
FORCEPROP 3 LASTPIN (800 4000) SIG_NAME M_H_DQS_DN<6>
J 0
(810 4010);
DISPLAY 0.659574 (810 4010);
PAINT MONO (810 4010);
DISPLAY INVISIBLE (810 4010);
FORCEPROP 1 LASTPIN (800 4000) BN 6
J 2
(850 4010);
DISPLAY 0.617021 (850 4010);
PAINT PINK (850 4010);
FORCEPROP 2 LAST CDS_LIB mstr_standard
J 0
(850 4000);
DISPLAY 0.787234 (850 4000);
PAINT MONO (850 4000);
DISPLAY INVISIBLE (850 4000);
FORCEPROP 1 LAST BODY_TYPE PLUMBING
J 2
(850 3950);
DISPLAY 1.234043 (850 3950);
PAINT GREEN (850 3950);
DISPLAY INVISIBLE (850 3950);
FORCEPROP 1 LAST HDL_TAP TRUE
J 2
(525 3875);
DISPLAY 1.234043 (525 3875);
PAINT GREEN (525 3875);
DISPLAY INVISIBLE (525 3875);
FORCEPROP 1 LAST PATH I28
J 2
(850 4000);
DISPLAY 0.936170 (850 4000);
PAINT GREEN (850 4000);
DISPLAY INVISIBLE (850 4000);
FORCEADD TAP..6
R 2
(850 3900);
FORCEPROP 3 LASTPIN (800 3900) SIG_NAME M_H_DQS_DN<5>
J 0
(810 3910);
DISPLAY 0.659574 (810 3910);
PAINT MONO (810 3910);
DISPLAY INVISIBLE (810 3910);
FORCEPROP 1 LASTPIN (800 3900) BN 5
J 2
(850 3910);
DISPLAY 0.617021 (850 3910);
PAINT PINK (850 3910);
FORCEPROP 2 LAST CDS_LIB mstr_standard
J 0
(850 3900);
DISPLAY 0.787234 (850 3900);
PAINT MONO (850 3900);
DISPLAY INVISIBLE (850 3900);
FORCEPROP 1 LAST BODY_TYPE PLUMBING
J 2
(850 3850);
DISPLAY 1.234043 (850 3850);
PAINT GREEN (850 3850);
DISPLAY INVISIBLE (850 3850);
FORCEPROP 1 LAST HDL_TAP TRUE
J 2
(525 3775);
DISPLAY 1.234043 (525 3775);
PAINT GREEN (525 3775);
DISPLAY INVISIBLE (525 3775);
FORCEPROP 1 LAST PATH I29
J 2
(850 3900);
DISPLAY 0.936170 (850 3900);
PAINT GREEN (850 3900);
DISPLAY INVISIBLE (850 3900);
FORCEADD TAP..6
R 2
(850 5100);
FORCEPROP 3 LASTPIN (800 5100) SIG_NAME M_H_DQS_DN<17>
J 0
(810 5110);
DISPLAY 0.659574 (810 5110);
PAINT MONO (810 5110);
DISPLAY INVISIBLE (810 5110);
FORCEPROP 1 LASTPIN (800 5100) BN 17
J 2
(850 5110);
DISPLAY 0.617021 (850 5110);
PAINT PINK (850 5110);
FORCEPROP 2 LAST CDS_LIB mstr_standard
J 2
(850 5100);
DISPLAY 0.787234 (850 5100);
PAINT MONO (850 5100);
DISPLAY INVISIBLE (850 5100);
FORCEPROP 1 LAST BODY_TYPE PLUMBING
J 2
(850 5050);
DISPLAY 1.234043 (850 5050);
PAINT GREEN (850 5050);
DISPLAY INVISIBLE (850 5050);
FORCEPROP 1 LAST HDL_TAP TRUE
J 2
(525 4975);
DISPLAY 1.234043 (525 4975);
PAINT GREEN (525 4975);
DISPLAY INVISIBLE (525 4975);
FORCEPROP 1 LAST PATH I3
J 2
(850 5100);
DISPLAY 0.936170 (850 5100);
PAINT GREEN (850 5100);
DISPLAY INVISIBLE (850 5100);
FORCEADD TAP..6
R 2
(850 3700);
FORCEPROP 3 LASTPIN (800 3700) SIG_NAME M_H_DQS_DN<3>
J 0
(810 3710);
DISPLAY 0.659574 (810 3710);
PAINT MONO (810 3710);
DISPLAY INVISIBLE (810 3710);
FORCEPROP 1 LASTPIN (800 3700) BN 3
J 2
(850 3710);
DISPLAY 0.617021 (850 3710);
PAINT PINK (850 3710);
FORCEPROP 2 LAST CDS_LIB mstr_standard
J 0
(850 3700);
DISPLAY 0.787234 (850 3700);
PAINT MONO (850 3700);
DISPLAY INVISIBLE (850 3700);
FORCEPROP 1 LAST BODY_TYPE PLUMBING
J 2
(850 3650);
DISPLAY 1.234043 (850 3650);
PAINT GREEN (850 3650);
DISPLAY INVISIBLE (850 3650);
FORCEPROP 1 LAST HDL_TAP TRUE
J 2
(525 3575);
DISPLAY 1.234043 (525 3575);
PAINT GREEN (525 3575);
DISPLAY INVISIBLE (525 3575);
FORCEPROP 1 LAST PATH I30
J 2
(850 3700);
DISPLAY 0.936170 (850 3700);
PAINT GREEN (850 3700);
DISPLAY INVISIBLE (850 3700);
FORCEADD TAP..6
R 2
(850 3800);
FORCEPROP 3 LASTPIN (800 3800) SIG_NAME M_H_DQS_DN<4>
J 0
(810 3810);
DISPLAY 0.659574 (810 3810);
PAINT MONO (810 3810);
DISPLAY INVISIBLE (810 3810);
FORCEPROP 1 LASTPIN (800 3800) BN 4
J 2
(850 3810);
DISPLAY 0.617021 (850 3810);
PAINT PINK (850 3810);
FORCEPROP 2 LAST CDS_LIB mstr_standard
J 0
(850 3800);
DISPLAY 0.787234 (850 3800);
PAINT MONO (850 3800);
DISPLAY INVISIBLE (850 3800);
FORCEPROP 1 LAST BODY_TYPE PLUMBING
J 2
(850 3750);
DISPLAY 1.234043 (850 3750);
PAINT GREEN (850 3750);
DISPLAY INVISIBLE (850 3750);
FORCEPROP 1 LAST HDL_TAP TRUE
J 2
(525 3675);
DISPLAY 1.234043 (525 3675);
PAINT GREEN (525 3675);
DISPLAY INVISIBLE (525 3675);
FORCEPROP 1 LAST PATH I31
J 2
(850 3800);
DISPLAY 0.936170 (850 3800);
PAINT GREEN (850 3800);
DISPLAY INVISIBLE (850 3800);
FORCEADD TAP..6
R 2
(650 4050);
FORCEPROP 3 LASTPIN (600 4050) SIG_NAME M_H_DQS_DP<6>
J 0
(610 4060);
DISPLAY 0.659574 (610 4060);
PAINT MONO (610 4060);
DISPLAY INVISIBLE (610 4060);
FORCEPROP 1 LASTPIN (600 4050) BN 6
J 2
(650 4060);
DISPLAY 0.617021 (650 4060);
PAINT PINK (650 4060);
FORCEPROP 2 LAST CDS_LIB mstr_standard
J 0
(650 4050);
DISPLAY 0.787234 (650 4050);
PAINT MONO (650 4050);
DISPLAY INVISIBLE (650 4050);
FORCEPROP 1 LAST BODY_TYPE PLUMBING
J 2
(650 4000);
DISPLAY 1.234043 (650 4000);
PAINT GREEN (650 4000);
DISPLAY INVISIBLE (650 4000);
FORCEPROP 1 LAST HDL_TAP TRUE
J 2
(325 3925);
DISPLAY 1.234043 (325 3925);
PAINT GREEN (325 3925);
DISPLAY INVISIBLE (325 3925);
FORCEPROP 1 LAST PATH I32
J 2
(650 4050);
DISPLAY 0.936170 (650 4050);
PAINT GREEN (650 4050);
DISPLAY INVISIBLE (650 4050);
FORCEADD TAP..6
R 2
(650 3950);
FORCEPROP 3 LASTPIN (600 3950) SIG_NAME M_H_DQS_DP<5>
J 0
(610 3960);
DISPLAY 0.659574 (610 3960);
PAINT MONO (610 3960);
DISPLAY INVISIBLE (610 3960);
FORCEPROP 1 LASTPIN (600 3950) BN 5
J 2
(650 3960);
DISPLAY 0.617021 (650 3960);
PAINT PINK (650 3960);
FORCEPROP 2 LAST CDS_LIB mstr_standard
J 0
(650 3950);
DISPLAY 0.787234 (650 3950);
PAINT MONO (650 3950);
DISPLAY INVISIBLE (650 3950);
FORCEPROP 1 LAST BODY_TYPE PLUMBING
J 2
(650 3900);
DISPLAY 1.234043 (650 3900);
PAINT GREEN (650 3900);
DISPLAY INVISIBLE (650 3900);
FORCEPROP 1 LAST HDL_TAP TRUE
J 2
(325 3825);
DISPLAY 1.234043 (325 3825);
PAINT GREEN (325 3825);
DISPLAY INVISIBLE (325 3825);
FORCEPROP 1 LAST PATH I33
J 2
(650 3950);
DISPLAY 0.936170 (650 3950);
PAINT GREEN (650 3950);
DISPLAY INVISIBLE (650 3950);
FORCEADD TAP..6
R 2
(650 3850);
FORCEPROP 3 LASTPIN (600 3850) SIG_NAME M_H_DQS_DP<4>
J 0
(610 3860);
DISPLAY 0.659574 (610 3860);
PAINT MONO (610 3860);
DISPLAY INVISIBLE (610 3860);
FORCEPROP 1 LASTPIN (600 3850) BN 4
J 2
(650 3860);
DISPLAY 0.617021 (650 3860);
PAINT PINK (650 3860);
FORCEPROP 2 LAST CDS_LIB mstr_standard
J 0
(650 3850);
DISPLAY 0.787234 (650 3850);
PAINT MONO (650 3850);
DISPLAY INVISIBLE (650 3850);
FORCEPROP 1 LAST BODY_TYPE PLUMBING
J 2
(650 3800);
DISPLAY 1.234043 (650 3800);
PAINT GREEN (650 3800);
DISPLAY INVISIBLE (650 3800);
FORCEPROP 1 LAST HDL_TAP TRUE
J 2
(325 3725);
DISPLAY 1.234043 (325 3725);
PAINT GREEN (325 3725);
DISPLAY INVISIBLE (325 3725);
FORCEPROP 1 LAST PATH I34
J 2
(650 3850);
DISPLAY 0.936170 (650 3850);
PAINT GREEN (650 3850);
DISPLAY INVISIBLE (650 3850);
FORCEADD TAP..6
R 2
(650 3750);
FORCEPROP 3 LASTPIN (600 3750) SIG_NAME M_H_DQS_DP<3>
J 0
(610 3760);
DISPLAY 0.659574 (610 3760);
PAINT MONO (610 3760);
DISPLAY INVISIBLE (610 3760);
FORCEPROP 1 LASTPIN (600 3750) BN 3
J 2
(650 3760);
DISPLAY 0.617021 (650 3760);
PAINT PINK (650 3760);
FORCEPROP 2 LAST CDS_LIB mstr_standard
J 0
(650 3750);
DISPLAY 0.787234 (650 3750);
PAINT MONO (650 3750);
DISPLAY INVISIBLE (650 3750);
FORCEPROP 1 LAST BODY_TYPE PLUMBING
J 2
(650 3700);
DISPLAY 1.234043 (650 3700);
PAINT GREEN (650 3700);
DISPLAY INVISIBLE (650 3700);
FORCEPROP 1 LAST HDL_TAP TRUE
J 2
(325 3625);
DISPLAY 1.234043 (325 3625);
PAINT GREEN (325 3625);
DISPLAY INVISIBLE (325 3625);
FORCEPROP 1 LAST PATH I35
J 2
(650 3750);
DISPLAY 0.936170 (650 3750);
PAINT GREEN (650 3750);
DISPLAY INVISIBLE (650 3750);
FORCEADD TAP..6
R 2
(650 3650);
FORCEPROP 3 LASTPIN (600 3650) SIG_NAME M_H_DQS_DP<2>
J 0
(610 3660);
DISPLAY 0.659574 (610 3660);
PAINT MONO (610 3660);
DISPLAY INVISIBLE (610 3660);
FORCEPROP 1 LASTPIN (600 3650) BN 2
J 2
(650 3660);
DISPLAY 0.617021 (650 3660);
PAINT PINK (650 3660);
FORCEPROP 2 LAST CDS_LIB mstr_standard
J 0
(650 3650);
DISPLAY 0.787234 (650 3650);
PAINT MONO (650 3650);
DISPLAY INVISIBLE (650 3650);
FORCEPROP 1 LAST BODY_TYPE PLUMBING
J 2
(650 3600);
DISPLAY 1.234043 (650 3600);
PAINT GREEN (650 3600);
DISPLAY INVISIBLE (650 3600);
FORCEPROP 1 LAST HDL_TAP TRUE
J 2
(325 3525);
DISPLAY 1.234043 (325 3525);
PAINT GREEN (325 3525);
DISPLAY INVISIBLE (325 3525);
FORCEPROP 1 LAST PATH I36
J 2
(650 3650);
DISPLAY 0.936170 (650 3650);
PAINT GREEN (650 3650);
DISPLAY INVISIBLE (650 3650);
FORCEADD TAP..6
R 2
(850 3500);
FORCEPROP 3 LASTPIN (800 3500) SIG_NAME M_H_DQS_DN<1>
J 0
(810 3510);
DISPLAY 0.659574 (810 3510);
PAINT MONO (810 3510);
DISPLAY INVISIBLE (810 3510);
FORCEPROP 1 LASTPIN (800 3500) BN 1
J 2
(850 3510);
DISPLAY 0.617021 (850 3510);
PAINT PINK (850 3510);
FORCEPROP 2 LAST CDS_LIB mstr_standard
J 0
(850 3500);
DISPLAY 0.787234 (850 3500);
PAINT MONO (850 3500);
DISPLAY INVISIBLE (850 3500);
FORCEPROP 1 LAST BODY_TYPE PLUMBING
J 2
(850 3450);
DISPLAY 1.234043 (850 3450);
PAINT GREEN (850 3450);
DISPLAY INVISIBLE (850 3450);
FORCEPROP 1 LAST HDL_TAP TRUE
J 2
(525 3375);
DISPLAY 1.234043 (525 3375);
PAINT GREEN (525 3375);
DISPLAY INVISIBLE (525 3375);
FORCEPROP 1 LAST PATH I37
J 2
(850 3500);
DISPLAY 0.936170 (850 3500);
PAINT GREEN (850 3500);
DISPLAY INVISIBLE (850 3500);
FORCEADD TAP..6
R 2
(850 3600);
FORCEPROP 3 LASTPIN (800 3600) SIG_NAME M_H_DQS_DN<2>
J 0
(810 3610);
DISPLAY 0.659574 (810 3610);
PAINT MONO (810 3610);
DISPLAY INVISIBLE (810 3610);
FORCEPROP 1 LASTPIN (800 3600) BN 2
J 2
(850 3610);
DISPLAY 0.617021 (850 3610);
PAINT PINK (850 3610);
FORCEPROP 2 LAST CDS_LIB mstr_standard
J 0
(850 3600);
DISPLAY 0.787234 (850 3600);
PAINT MONO (850 3600);
DISPLAY INVISIBLE (850 3600);
FORCEPROP 1 LAST BODY_TYPE PLUMBING
J 2
(850 3550);
DISPLAY 1.234043 (850 3550);
PAINT GREEN (850 3550);
DISPLAY INVISIBLE (850 3550);
FORCEPROP 1 LAST HDL_TAP TRUE
J 2
(525 3475);
DISPLAY 1.234043 (525 3475);
PAINT GREEN (525 3475);
DISPLAY INVISIBLE (525 3475);
FORCEPROP 1 LAST PATH I38
J 2
(850 3600);
DISPLAY 0.936170 (850 3600);
PAINT GREEN (850 3600);
DISPLAY INVISIBLE (850 3600);
FORCEADD TAP..6
R 2
(850 3400);
FORCEPROP 3 LASTPIN (800 3400) SIG_NAME M_H_DQS_DN<0>
J 0
(810 3410);
DISPLAY 0.659574 (810 3410);
PAINT MONO (810 3410);
DISPLAY INVISIBLE (810 3410);
FORCEPROP 1 LASTPIN (800 3400) BN 0
J 2
(850 3410);
DISPLAY 0.617021 (850 3410);
PAINT PINK (850 3410);
FORCEPROP 2 LAST CDS_LIB mstr_standard
J 0
(850 3400);
DISPLAY 0.787234 (850 3400);
PAINT MONO (850 3400);
DISPLAY INVISIBLE (850 3400);
FORCEPROP 1 LAST BODY_TYPE PLUMBING
J 2
(850 3350);
DISPLAY 1.234043 (850 3350);
PAINT GREEN (850 3350);
DISPLAY INVISIBLE (850 3350);
FORCEPROP 1 LAST HDL_TAP TRUE
J 2
(525 3275);
DISPLAY 1.234043 (525 3275);
PAINT GREEN (525 3275);
DISPLAY INVISIBLE (525 3275);
FORCEPROP 1 LAST PATH I39
J 2
(850 3400);
DISPLAY 0.936170 (850 3400);
PAINT GREEN (850 3400);
DISPLAY INVISIBLE (850 3400);
FORCEADD TAP..6
R 2
(850 5000);
FORCEPROP 3 LASTPIN (800 5000) SIG_NAME M_H_DQS_DN<16>
J 0
(810 5010);
DISPLAY 0.659574 (810 5010);
PAINT MONO (810 5010);
DISPLAY INVISIBLE (810 5010);
FORCEPROP 1 LASTPIN (800 5000) BN 16
J 2
(850 5010);
DISPLAY 0.617021 (850 5010);
PAINT PINK (850 5010);
FORCEPROP 2 LAST CDS_LIB mstr_standard
J 0
(850 5000);
DISPLAY 0.787234 (850 5000);
PAINT MONO (850 5000);
DISPLAY INVISIBLE (850 5000);
FORCEPROP 1 LAST BODY_TYPE PLUMBING
J 2
(850 4950);
DISPLAY 1.234043 (850 4950);
PAINT GREEN (850 4950);
DISPLAY INVISIBLE (850 4950);
FORCEPROP 1 LAST HDL_TAP TRUE
J 2
(525 4875);
DISPLAY 1.234043 (525 4875);
PAINT GREEN (525 4875);
DISPLAY INVISIBLE (525 4875);
FORCEPROP 1 LAST PATH I4
J 2
(850 5000);
DISPLAY 0.936170 (850 5000);
PAINT GREEN (850 5000);
DISPLAY INVISIBLE (850 5000);
FORCEADD TAP..6
R 2
(650 3550);
FORCEPROP 3 LASTPIN (600 3550) SIG_NAME M_H_DQS_DP<1>
J 0
(610 3560);
DISPLAY 0.659574 (610 3560);
PAINT MONO (610 3560);
DISPLAY INVISIBLE (610 3560);
FORCEPROP 1 LASTPIN (600 3550) BN 1
J 2
(650 3560);
DISPLAY 0.617021 (650 3560);
PAINT PINK (650 3560);
FORCEPROP 2 LAST CDS_LIB mstr_standard
J 0
(650 3550);
DISPLAY 0.787234 (650 3550);
PAINT MONO (650 3550);
DISPLAY INVISIBLE (650 3550);
FORCEPROP 1 LAST BODY_TYPE PLUMBING
J 2
(650 3500);
DISPLAY 1.234043 (650 3500);
PAINT GREEN (650 3500);
DISPLAY INVISIBLE (650 3500);
FORCEPROP 1 LAST HDL_TAP TRUE
J 2
(325 3425);
DISPLAY 1.234043 (325 3425);
PAINT GREEN (325 3425);
DISPLAY INVISIBLE (325 3425);
FORCEPROP 1 LAST PATH I40
J 2
(650 3550);
DISPLAY 0.936170 (650 3550);
PAINT GREEN (650 3550);
DISPLAY INVISIBLE (650 3550);
FORCEADD SCONN288_H44441004..3
(1750 2400);
FORCEPROP 2 LASTPIN (1250 1900) $PN 109
J 2
(1240 1910);
DISPLAY 0.617021 (1240 1910);
PAINT ORANGE (1240 1910);
FORCEPROP 2 LASTPIN (1250 1850) $PN 112
J 2
(1240 1860);
DISPLAY 0.617021 (1240 1860);
PAINT ORANGE (1240 1860);
FORCEPROP 1 LAST LOCATION J1G2
J 0
(1300 3800);
DISPLAY 0.617021 (1300 3800);
PAINT AQUA (1300 3800);
FORCEPROP 1 LAST PART_NUMBER H44441-004
J 0
(1300 1050);
DISPLAY 0.617021 (1300 1050);
PAINT BLUE (1300 1050);
FORCEPROP 1 LAST MATERIAL SCONN
J 0
(1300 3750);
DISPLAY 0.617021 (1300 3750);
PAINT SKYBLUE (1300 3750);
FORCEPROP 2 LASTPIN (1250 3550) $PN 2
J 2
(1240 3560);
DISPLAY 0.617021 (1240 3560);
PAINT ORANGE (1240 3560);
FORCEPROP 2 LASTPIN (1250 3500) $PN 4
J 2
(1240 3510);
DISPLAY 0.617021 (1240 3510);
PAINT ORANGE (1240 3510);
FORCEPROP 2 LASTPIN (1250 3450) $PN 6
J 2
(1240 3460);
DISPLAY 0.617021 (1240 3460);
PAINT ORANGE (1240 3460);
FORCEPROP 2 LASTPIN (1250 3400) $PN 9
J 2
(1240 3410);
DISPLAY 0.617021 (1240 3410);
PAINT ORANGE (1240 3410);
FORCEPROP 2 LASTPIN (1250 3350) $PN 11
J 2
(1240 3360);
DISPLAY 0.617021 (1240 3360);
PAINT ORANGE (1240 3360);
FORCEPROP 2 LASTPIN (1250 3300) $PN 13
J 2
(1240 3310);
DISPLAY 0.617021 (1240 3310);
PAINT ORANGE (1240 3310);
FORCEPROP 2 LASTPIN (1250 3250) $PN 15
J 2
(1240 3260);
DISPLAY 0.617021 (1240 3260);
PAINT ORANGE (1240 3260);
FORCEPROP 2 LASTPIN (1250 3200) $PN 17
J 2
(1240 3210);
DISPLAY 0.617021 (1240 3210);
PAINT ORANGE (1240 3210);
FORCEPROP 2 LASTPIN (1250 3150) $PN 20
J 2
(1240 3160);
DISPLAY 0.617021 (1240 3160);
PAINT ORANGE (1240 3160);
FORCEPROP 2 LASTPIN (1250 3100) $PN 22
J 2
(1240 3110);
DISPLAY 0.617021 (1240 3110);
PAINT ORANGE (1240 3110);
FORCEPROP 2 LASTPIN (1250 3000) $PN 26
J 2
(1240 3010);
DISPLAY 0.617021 (1240 3010);
PAINT ORANGE (1240 3010);
FORCEPROP 2 LASTPIN (1250 2950) $PN 28
J 2
(1240 2960);
DISPLAY 0.617021 (1240 2960);
PAINT ORANGE (1240 2960);
FORCEPROP 2 LASTPIN (1250 2900) $PN 31
J 2
(1240 2910);
DISPLAY 0.617021 (1240 2910);
PAINT ORANGE (1240 2910);
FORCEPROP 2 LASTPIN (1250 2850) $PN 33
J 2
(1240 2860);
DISPLAY 0.617021 (1240 2860);
PAINT ORANGE (1240 2860);
FORCEPROP 2 LASTPIN (1250 2800) $PN 35
J 2
(1240 2810);
DISPLAY 0.617021 (1240 2810);
PAINT ORANGE (1240 2810);
FORCEPROP 2 LASTPIN (1250 2750) $PN 37
J 2
(1240 2760);
DISPLAY 0.617021 (1240 2760);
PAINT ORANGE (1240 2760);
FORCEPROP 2 LASTPIN (1250 2700) $PN 39
J 2
(1240 2710);
DISPLAY 0.617021 (1240 2710);
PAINT ORANGE (1240 2710);
FORCEPROP 2 LASTPIN (1250 2650) $PN 42
J 2
(1240 2660);
DISPLAY 0.617021 (1240 2660);
PAINT ORANGE (1240 2660);
FORCEPROP 2 LASTPIN (1250 2600) $PN 44
J 2
(1240 2610);
DISPLAY 0.617021 (1240 2610);
PAINT ORANGE (1240 2610);
FORCEPROP 2 LASTPIN (1250 2550) $PN 46
J 2
(1240 2560);
DISPLAY 0.617021 (1240 2560);
PAINT ORANGE (1240 2560);
FORCEPROP 2 LASTPIN (1250 2500) $PN 48
J 2
(1240 2510);
DISPLAY 0.617021 (1240 2510);
PAINT ORANGE (1240 2510);
FORCEPROP 2 LASTPIN (1250 2450) $PN 50
J 2
(1240 2460);
DISPLAY 0.617021 (1240 2460);
PAINT ORANGE (1240 2460);
FORCEPROP 2 LASTPIN (1250 2400) $PN 53
J 2
(1240 2410);
DISPLAY 0.617021 (1240 2410);
PAINT ORANGE (1240 2410);
FORCEPROP 2 LASTPIN (1250 2350) $PN 55
J 2
(1240 2360);
DISPLAY 0.617021 (1240 2360);
PAINT ORANGE (1240 2360);
FORCEPROP 2 LASTPIN (1250 2300) $PN 57
J 2
(1240 2310);
DISPLAY 0.617021 (1240 2310);
PAINT ORANGE (1240 2310);
FORCEPROP 2 LASTPIN (1250 2250) $PN 94
J 2
(1240 2260);
DISPLAY 0.617021 (1240 2260);
PAINT ORANGE (1240 2260);
FORCEPROP 2 LASTPIN (1250 2200) $PN 96
J 2
(1240 2210);
DISPLAY 0.617021 (1240 2210);
PAINT ORANGE (1240 2210);
FORCEPROP 2 LASTPIN (1250 2150) $PN 98
J 2
(1240 2160);
DISPLAY 0.617021 (1240 2160);
PAINT ORANGE (1240 2160);
FORCEPROP 2 LASTPIN (1250 2100) $PN 101
J 2
(1240 2110);
DISPLAY 0.617021 (1240 2110);
PAINT ORANGE (1240 2110);
FORCEPROP 2 LASTPIN (1250 2050) $PN 103
J 2
(1240 2060);
DISPLAY 0.617021 (1240 2060);
PAINT ORANGE (1240 2060);
FORCEPROP 2 LASTPIN (1250 2000) $PN 105
J 2
(1240 2010);
DISPLAY 0.617021 (1240 2010);
PAINT ORANGE (1240 2010);
FORCEPROP 2 LASTPIN (1250 1950) $PN 107
J 2
(1240 1960);
DISPLAY 0.617021 (1240 1960);
PAINT ORANGE (1240 1960);
FORCEPROP 2 LASTPIN (1250 1800) $PN 114
J 2
(1240 1810);
DISPLAY 0.617021 (1240 1810);
PAINT ORANGE (1240 1810);
FORCEPROP 2 LASTPIN (1250 1750) $PN 116
J 2
(1240 1760);
DISPLAY 0.617021 (1240 1760);
PAINT ORANGE (1240 1760);
FORCEPROP 2 LASTPIN (1250 1700) $PN 118
J 2
(1240 1710);
DISPLAY 0.617021 (1240 1710);
PAINT ORANGE (1240 1710);
FORCEPROP 2 LASTPIN (1250 1650) $PN 120
J 2
(1240 1660);
DISPLAY 0.617021 (1240 1660);
PAINT ORANGE (1240 1660);
FORCEPROP 2 LASTPIN (1250 1600) $PN 123
J 2
(1240 1610);
DISPLAY 0.617021 (1240 1610);
PAINT ORANGE (1240 1610);
FORCEPROP 2 LASTPIN (1250 1550) $PN 125
J 2
(1240 1560);
DISPLAY 0.617021 (1240 1560);
PAINT ORANGE (1240 1560);
FORCEPROP 2 LASTPIN (1250 1500) $PN 127
J 2
(1240 1510);
DISPLAY 0.617021 (1240 1510);
PAINT ORANGE (1240 1510);
FORCEPROP 2 LASTPIN (1250 1450) $PN 129
J 2
(1240 1460);
DISPLAY 0.617021 (1240 1460);
PAINT ORANGE (1240 1460);
FORCEPROP 2 LASTPIN (1250 1400) $PN 131
J 2
(1240 1410);
DISPLAY 0.617021 (1240 1410);
PAINT ORANGE (1240 1410);
FORCEPROP 2 LASTPIN (1250 1350) $PN 134
J 2
(1240 1360);
DISPLAY 0.617021 (1240 1360);
PAINT ORANGE (1240 1360);
FORCEPROP 2 LASTPIN (1250 1300) $PN 136
J 2
(1240 1310);
DISPLAY 0.617021 (1240 1310);
PAINT ORANGE (1240 1310);
FORCEPROP 2 LASTPIN (1250 1250) $PN 138
J 2
(1240 1260);
DISPLAY 0.617021 (1240 1260);
PAINT ORANGE (1240 1260);
FORCEPROP 2 LASTPIN (2250 3550) $PN 147
J 0
(2260 3560);
DISPLAY 0.617021 (2260 3560);
PAINT ORANGE (2260 3560);
FORCEPROP 2 LASTPIN (2250 3500) $PN 149
J 0
(2260 3510);
DISPLAY 0.617021 (2260 3510);
PAINT ORANGE (2260 3510);
FORCEPROP 2 LASTPIN (2250 3450) $PN 151
J 0
(2260 3460);
DISPLAY 0.617021 (2260 3460);
PAINT ORANGE (2260 3460);
FORCEPROP 2 LASTPIN (2250 3400) $PN 154
J 0
(2260 3410);
DISPLAY 0.617021 (2260 3410);
PAINT ORANGE (2260 3410);
FORCEPROP 2 LASTPIN (2250 3350) $PN 156
J 0
(2260 3360);
DISPLAY 0.617021 (2260 3360);
PAINT ORANGE (2260 3360);
FORCEPROP 2 LASTPIN (2250 3300) $PN 158
J 0
(2260 3310);
DISPLAY 0.617021 (2260 3310);
PAINT ORANGE (2260 3310);
FORCEPROP 2 LASTPIN (2250 3250) $PN 160
J 0
(2260 3260);
DISPLAY 0.617021 (2260 3260);
PAINT ORANGE (2260 3260);
FORCEPROP 2 LASTPIN (2250 3200) $PN 162
J 0
(2260 3210);
DISPLAY 0.617021 (2260 3210);
PAINT ORANGE (2260 3210);
FORCEPROP 2 LASTPIN (2250 3150) $PN 165
J 0
(2260 3160);
DISPLAY 0.617021 (2260 3160);
PAINT ORANGE (2260 3160);
FORCEPROP 2 LASTPIN (2250 3100) $PN 167
J 0
(2260 3110);
DISPLAY 0.617021 (2260 3110);
PAINT ORANGE (2260 3110);
FORCEPROP 2 LASTPIN (2250 3050) $PN 169
J 0
(2260 3060);
DISPLAY 0.617021 (2260 3060);
PAINT ORANGE (2260 3060);
FORCEPROP 2 LASTPIN (2250 3000) $PN 171
J 0
(2260 3010);
DISPLAY 0.617021 (2260 3010);
PAINT ORANGE (2260 3010);
FORCEPROP 2 LASTPIN (2250 2950) $PN 173
J 0
(2260 2960);
DISPLAY 0.617021 (2260 2960);
PAINT ORANGE (2260 2960);
FORCEPROP 2 LASTPIN (2250 2900) $PN 176
J 0
(2260 2910);
DISPLAY 0.617021 (2260 2910);
PAINT ORANGE (2260 2910);
FORCEPROP 2 LASTPIN (2250 2850) $PN 178
J 0
(2260 2860);
DISPLAY 0.617021 (2260 2860);
PAINT ORANGE (2260 2860);
FORCEPROP 2 LASTPIN (2250 2800) $PN 180
J 0
(2260 2810);
DISPLAY 0.617021 (2260 2810);
PAINT ORANGE (2260 2810);
FORCEPROP 2 LASTPIN (2250 2750) $PN 182
J 0
(2260 2760);
DISPLAY 0.617021 (2260 2760);
PAINT ORANGE (2260 2760);
FORCEPROP 2 LASTPIN (2250 2700) $PN 184
J 0
(2260 2710);
DISPLAY 0.617021 (2260 2710);
PAINT ORANGE (2260 2710);
FORCEPROP 2 LASTPIN (2250 2650) $PN 187
J 0
(2260 2660);
DISPLAY 0.617021 (2260 2660);
PAINT ORANGE (2260 2660);
FORCEPROP 2 LASTPIN (2250 2600) $PN 189
J 0
(2260 2610);
DISPLAY 0.617021 (2260 2610);
PAINT ORANGE (2260 2610);
FORCEPROP 2 LASTPIN (2250 2550) $PN 191
J 0
(2260 2560);
DISPLAY 0.617021 (2260 2560);
PAINT ORANGE (2260 2560);
FORCEPROP 2 LASTPIN (2250 2500) $PN 193
J 0
(2260 2510);
DISPLAY 0.617021 (2260 2510);
PAINT ORANGE (2260 2510);
FORCEPROP 2 LASTPIN (2250 2450) $PN 195
J 0
(2260 2460);
DISPLAY 0.617021 (2260 2460);
PAINT ORANGE (2260 2460);
FORCEPROP 2 LASTPIN (2250 2400) $PN 198
J 0
(2260 2410);
DISPLAY 0.617021 (2260 2410);
PAINT ORANGE (2260 2410);
FORCEPROP 2 LASTPIN (2250 2350) $PN 200
J 0
(2260 2360);
DISPLAY 0.617021 (2260 2360);
PAINT ORANGE (2260 2360);
FORCEPROP 2 LASTPIN (2250 2300) $PN 202
J 0
(2260 2310);
DISPLAY 0.617021 (2260 2310);
PAINT ORANGE (2260 2310);
FORCEPROP 2 LASTPIN (2250 2250) $PN 239
J 0
(2260 2260);
DISPLAY 0.617021 (2260 2260);
PAINT ORANGE (2260 2260);
FORCEPROP 2 LASTPIN (2250 2200) $PN 241
J 0
(2260 2210);
DISPLAY 0.617021 (2260 2210);
PAINT ORANGE (2260 2210);
FORCEPROP 2 LASTPIN (2250 2150) $PN 243
J 0
(2260 2160);
DISPLAY 0.617021 (2260 2160);
PAINT ORANGE (2260 2160);
FORCEPROP 2 LASTPIN (2250 2100) $PN 246
J 0
(2260 2110);
DISPLAY 0.617021 (2260 2110);
PAINT ORANGE (2260 2110);
FORCEPROP 2 LASTPIN (2250 2050) $PN 248
J 0
(2260 2060);
DISPLAY 0.617021 (2260 2060);
PAINT ORANGE (2260 2060);
FORCEPROP 2 LASTPIN (2250 2000) $PN 250
J 0
(2260 2010);
DISPLAY 0.617021 (2260 2010);
PAINT ORANGE (2260 2010);
FORCEPROP 2 LASTPIN (2250 1950) $PN 252
J 0
(2260 1960);
DISPLAY 0.617021 (2260 1960);
PAINT ORANGE (2260 1960);
FORCEPROP 2 LASTPIN (2250 1900) $PN 254
J 0
(2260 1910);
DISPLAY 0.617021 (2260 1910);
PAINT ORANGE (2260 1910);
FORCEPROP 2 LASTPIN (2250 1850) $PN 257
J 0
(2260 1860);
DISPLAY 0.617021 (2260 1860);
PAINT ORANGE (2260 1860);
FORCEPROP 2 LASTPIN (2250 1800) $PN 259
J 0
(2260 1810);
DISPLAY 0.617021 (2260 1810);
PAINT ORANGE (2260 1810);
FORCEPROP 2 LASTPIN (2250 1750) $PN 261
J 0
(2260 1760);
DISPLAY 0.617021 (2260 1760);
PAINT ORANGE (2260 1760);
FORCEPROP 2 LASTPIN (2250 1700) $PN 263
J 0
(2260 1710);
DISPLAY 0.617021 (2260 1710);
PAINT ORANGE (2260 1710);
FORCEPROP 2 LASTPIN (2250 1650) $PN 265
J 0
(2260 1660);
DISPLAY 0.617021 (2260 1660);
PAINT ORANGE (2260 1660);
FORCEPROP 2 LASTPIN (2250 1600) $PN 268
J 0
(2260 1610);
DISPLAY 0.617021 (2260 1610);
PAINT ORANGE (2260 1610);
FORCEPROP 2 LASTPIN (2250 1550) $PN 270
J 0
(2260 1560);
DISPLAY 0.617021 (2260 1560);
PAINT ORANGE (2260 1560);
FORCEPROP 2 LASTPIN (2250 1500) $PN 272
J 0
(2260 1510);
DISPLAY 0.617021 (2260 1510);
PAINT ORANGE (2260 1510);
FORCEPROP 2 LASTPIN (2250 1450) $PN 274
J 0
(2260 1460);
DISPLAY 0.617021 (2260 1460);
PAINT ORANGE (2260 1460);
FORCEPROP 2 LASTPIN (2250 1400) $PN 276
J 0
(2260 1410);
DISPLAY 0.617021 (2260 1410);
PAINT ORANGE (2260 1410);
FORCEPROP 2 LASTPIN (2250 1350) $PN 279
J 0
(2260 1360);
DISPLAY 0.617021 (2260 1360);
PAINT ORANGE (2260 1360);
FORCEPROP 2 LASTPIN (2250 1300) $PN 281
J 0
(2260 1310);
DISPLAY 0.617021 (2260 1310);
PAINT ORANGE (2260 1310);
FORCEPROP 2 LASTPIN (2250 1250) $PN 283
J 0
(2260 1260);
DISPLAY 0.617021 (2260 1260);
PAINT ORANGE (2260 1260);
FORCEPROP 2 LASTPIN (1250 3050) $PN 24
J 2
(1240 3060);
DISPLAY 0.617021 (1240 3060);
PAINT ORANGE (1240 3060);
FORCEPROP 1 LAST PACK_TYPE PIP
J 0
(1300 3850);
PAINT SKYBLUE (1300 3850);
DISPLAY INVISIBLE (1300 3850);
FORCEPROP 2 LAST BOM_COST MEM
J 0
(1750 2400);
PAINT ORANGE (1750 2400);
DISPLAY INVISIBLE (1750 2400);
FORCEPROP 2 LAST CDS_LIB mstr_sconn
J 0
(1750 2400);
PAINT ORANGE (1750 2400);
DISPLAY INVISIBLE (1750 2400);
FORCEPROP 2 LAST SEC_TYPE PIP
J 0
(1300 3850);
DISPLAY 1.021277 (1300 3850);
PAINT ORANGE (1300 3850);
DISPLAY INVISIBLE (1300 3850);
FORCEPROP 2 LAST SEC 3
J 0
(1300 3850);
DISPLAY 0.680851 (1300 3850);
PAINT MONO (1300 3850);
DISPLAY INVISIBLE (1300 3850);
FORCEPROP 2 LAST CDS_LOCATION J1G2
J 0
(1300 3800);
DISPLAY 0.617021 (1300 3800);
PAINT AQUA (1300 3800);
DISPLAY INVISIBLE (1300 3800);
FORCEPROP 1 LAST PATH I43
J 0
(1750 3750);
PAINT GREEN (1750 3750);
DISPLAY INVISIBLE (1750 3750);
FORCEPROP 2 LAST ROOM DDR4_CH_H
J 0
(1750 2400);
PAINT ORANGE (1750 2400);
DISPLAY INVISIBLE (1750 2400);
FORCEADD GND..1
R 2
(1050 1100);
FORCEPROP 3 LASTPIN (1050 1150) SIG_NAME GND\g
J 0
(1060 1160);
DISPLAY 0.659574 (1060 1160);
PAINT MONO (1060 1160);
DISPLAY INVISIBLE (1060 1160);
FORCEPROP 1 LAST VOLTAGE 0
J 0
(1050 1100);
PAINT SKYBLUE (1050 1100);
DISPLAY INVISIBLE (1050 1100);
FORCEPROP 2 LAST CDS_LIB mstr_symbols
J 0
(1050 1100);
DISPLAY 0.787234 (1050 1100);
PAINT MONO (1050 1100);
DISPLAY INVISIBLE (1050 1100);
FORCEPROP 1 LAST SIZE 1B
J 2
(975 1050);
DISPLAY 1.170213 (975 1050);
PAINT GREEN (975 1050);
DISPLAY INVISIBLE (975 1050);
FORCEPROP 2 LAST BOM_COST MEM
J 0
(1050 1105);
PAINT ORANGE (1050 1105);
DISPLAY INVISIBLE (1050 1105);
FORCEPROP 1 LAST BODY_TYPE PLUMBING
J 2
(1095 1057);
DISPLAY 0.340426 (1095 1057);
PAINT GREEN (1095 1057);
DISPLAY INVISIBLE (1095 1057);
FORCEPROP 1 LAST PATH I44
J 2
(975 1100);
DISPLAY 0.936170 (975 1100);
PAINT GREEN (975 1100);
DISPLAY INVISIBLE (975 1100);
FORCEPROP 2 LAST ROOM DDR4_CH_H
J 0
(1050 1105);
PAINT ORANGE (1050 1105);
DISPLAY INVISIBLE (1050 1105);
FORCEPROP 1 LAST HDL_POWER GND
J 2
(1050 1250);
DISPLAY 0.553191 (1050 1250);
PAINT GREEN (1050 1250);
DISPLAY INVISIBLE (1050 1250);
FORCEADD OFFPAGE..3
(-1250 4950);
FORCEPROP 2 LAST $XR1 80 
J 0
(-946 4950);
DISPLAY 0.638298 (-946 4950);
PAINT MONO (-946 4950);
FORCEPROP 2 LAST $XR0 58 
J 0
(-1036 4950);
DISPLAY 0.638298 (-1036 4950);
PAINT MONO (-1036 4950);
FORCEPROP 2 LAST CDS_LIB mstr_standard
J 0
(-1250 4950);
DISPLAY 0.787234 (-1250 4950);
PAINT MONO (-1250 4950);
DISPLAY INVISIBLE (-1250 4950);
FORCEPROP 1 LAST OFFPAGE TRUE
J 0
(-925 4825);
DISPLAY 0.936170 (-925 4825);
PAINT GREEN (-925 4825);
DISPLAY INVISIBLE (-925 4825);
FORCEPROP 1 LAST COMMENT_BODY TRUE
J 0
(-1300 4850);
DISPLAY 0.936170 (-1300 4850);
PAINT GREEN (-1300 4850);
DISPLAY INVISIBLE (-1300 4850);
FORCEPROP 2 LAST PATH I45
J 0
(-1050 5025);
DISPLAY 0.787234 (-1050 5025);
PAINT MONO (-1050 5025);
DISPLAY INVISIBLE (-1050 5025);
FORCEADD TAP..6
R 2
(-1850 4850);
FORCEPROP 3 LASTPIN (-1900 4850) SIG_NAME M_H_DQ<63>
J 0
(-1890 4860);
DISPLAY 0.659574 (-1890 4860);
PAINT MONO (-1890 4860);
DISPLAY INVISIBLE (-1890 4860);
FORCEPROP 1 LASTPIN (-1900 4850) BN 63
J 2
(-1850 4860);
DISPLAY 0.617021 (-1850 4860);
PAINT PINK (-1850 4860);
FORCEPROP 2 LAST CDS_LIB mstr_standard
J 2
(-1850 4850);
DISPLAY 0.787234 (-1850 4850);
PAINT MONO (-1850 4850);
DISPLAY INVISIBLE (-1850 4850);
FORCEPROP 1 LAST BODY_TYPE PLUMBING
J 2
(-1850 4800);
DISPLAY 1.234043 (-1850 4800);
PAINT GREEN (-1850 4800);
DISPLAY INVISIBLE (-1850 4800);
FORCEPROP 1 LAST HDL_TAP TRUE
J 2
(-2175 4725);
DISPLAY 1.234043 (-2175 4725);
PAINT GREEN (-2175 4725);
DISPLAY INVISIBLE (-2175 4725);
FORCEPROP 1 LAST PATH I46
J 2
(-1850 4850);
DISPLAY 0.936170 (-1850 4850);
PAINT GREEN (-1850 4850);
DISPLAY INVISIBLE (-1850 4850);
FORCEADD TAP..6
R 2
(-1850 4900);
FORCEPROP 3 LASTPIN (-1900 4900) SIG_NAME M_H_DQ<62>
J 0
(-1890 4910);
DISPLAY 0.659574 (-1890 4910);
PAINT MONO (-1890 4910);
DISPLAY INVISIBLE (-1890 4910);
FORCEPROP 1 LASTPIN (-1900 4900) BN 62
J 2
(-1850 4910);
DISPLAY 0.617021 (-1850 4910);
PAINT PINK (-1850 4910);
FORCEPROP 2 LAST CDS_LIB mstr_standard
J 2
(-1850 4900);
DISPLAY 0.787234 (-1850 4900);
PAINT MONO (-1850 4900);
DISPLAY INVISIBLE (-1850 4900);
FORCEPROP 1 LAST BODY_TYPE PLUMBING
J 2
(-1850 4850);
DISPLAY 1.234043 (-1850 4850);
PAINT GREEN (-1850 4850);
DISPLAY INVISIBLE (-1850 4850);
FORCEPROP 1 LAST HDL_TAP TRUE
J 2
(-2175 4775);
DISPLAY 1.234043 (-2175 4775);
PAINT GREEN (-2175 4775);
DISPLAY INVISIBLE (-2175 4775);
FORCEPROP 1 LAST PATH I47
J 2
(-1850 4900);
DISPLAY 0.936170 (-1850 4900);
PAINT GREEN (-1850 4900);
DISPLAY INVISIBLE (-1850 4900);
FORCEADD TAP..6
R 2
(-1850 4750);
FORCEPROP 3 LASTPIN (-1900 4750) SIG_NAME M_H_DQ<61>
J 0
(-1890 4760);
DISPLAY 0.659574 (-1890 4760);
PAINT MONO (-1890 4760);
DISPLAY INVISIBLE (-1890 4760);
FORCEPROP 1 LASTPIN (-1900 4750) BN 61
J 2
(-1850 4760);
DISPLAY 0.617021 (-1850 4760);
PAINT PINK (-1850 4760);
FORCEPROP 2 LAST CDS_LIB mstr_standard
J 2
(-1850 4750);
DISPLAY 0.787234 (-1850 4750);
PAINT MONO (-1850 4750);
DISPLAY INVISIBLE (-1850 4750);
FORCEPROP 1 LAST BODY_TYPE PLUMBING
J 2
(-1850 4700);
DISPLAY 1.234043 (-1850 4700);
PAINT GREEN (-1850 4700);
DISPLAY INVISIBLE (-1850 4700);
FORCEPROP 1 LAST HDL_TAP TRUE
J 2
(-2175 4625);
DISPLAY 1.234043 (-2175 4625);
PAINT GREEN (-2175 4625);
DISPLAY INVISIBLE (-2175 4625);
FORCEPROP 1 LAST PATH I48
J 2
(-1850 4750);
DISPLAY 0.936170 (-1850 4750);
PAINT GREEN (-1850 4750);
DISPLAY INVISIBLE (-1850 4750);
FORCEADD TAP..6
R 2
(-1850 4800);
FORCEPROP 3 LASTPIN (-1900 4800) SIG_NAME M_H_DQ<60>
J 0
(-1890 4810);
DISPLAY 0.659574 (-1890 4810);
PAINT MONO (-1890 4810);
DISPLAY INVISIBLE (-1890 4810);
FORCEPROP 1 LASTPIN (-1900 4800) BN 60
J 2
(-1850 4810);
DISPLAY 0.617021 (-1850 4810);
PAINT PINK (-1850 4810);
FORCEPROP 2 LAST CDS_LIB mstr_standard
J 2
(-1850 4800);
DISPLAY 0.787234 (-1850 4800);
PAINT MONO (-1850 4800);
DISPLAY INVISIBLE (-1850 4800);
FORCEPROP 1 LAST BODY_TYPE PLUMBING
J 2
(-1850 4750);
DISPLAY 1.234043 (-1850 4750);
PAINT GREEN (-1850 4750);
DISPLAY INVISIBLE (-1850 4750);
FORCEPROP 1 LAST HDL_TAP TRUE
J 2
(-2175 4675);
DISPLAY 1.234043 (-2175 4675);
PAINT GREEN (-2175 4675);
DISPLAY INVISIBLE (-2175 4675);
FORCEPROP 1 LAST PATH I49
J 2
(-1850 4800);
DISPLAY 0.936170 (-1850 4800);
PAINT GREEN (-1850 4800);
DISPLAY INVISIBLE (-1850 4800);
FORCEADD TAP..6
R 2
(850 4900);
FORCEPROP 3 LASTPIN (800 4900) SIG_NAME M_H_DQS_DN<15>
J 0
(810 4910);
DISPLAY 0.659574 (810 4910);
PAINT MONO (810 4910);
DISPLAY INVISIBLE (810 4910);
FORCEPROP 1 LASTPIN (800 4900) BN 15
J 2
(850 4910);
DISPLAY 0.617021 (850 4910);
PAINT PINK (850 4910);
FORCEPROP 2 LAST CDS_LIB mstr_standard
J 0
(850 4900);
DISPLAY 0.787234 (850 4900);
PAINT MONO (850 4900);
DISPLAY INVISIBLE (850 4900);
FORCEPROP 1 LAST BODY_TYPE PLUMBING
J 2
(850 4850);
DISPLAY 1.234043 (850 4850);
PAINT GREEN (850 4850);
DISPLAY INVISIBLE (850 4850);
FORCEPROP 1 LAST HDL_TAP TRUE
J 2
(525 4775);
DISPLAY 1.234043 (525 4775);
PAINT GREEN (525 4775);
DISPLAY INVISIBLE (525 4775);
FORCEPROP 1 LAST PATH I5
J 2
(850 4900);
DISPLAY 0.936170 (850 4900);
PAINT GREEN (850 4900);
DISPLAY INVISIBLE (850 4900);
FORCEADD TAP..6
R 2
(-1850 4700);
FORCEPROP 3 LASTPIN (-1900 4700) SIG_NAME M_H_DQ<58>
J 0
(-1890 4710);
DISPLAY 0.659574 (-1890 4710);
PAINT MONO (-1890 4710);
DISPLAY INVISIBLE (-1890 4710);
FORCEPROP 1 LASTPIN (-1900 4700) BN 58
J 2
(-1850 4710);
DISPLAY 0.617021 (-1850 4710);
PAINT PINK (-1850 4710);
FORCEPROP 2 LAST CDS_LIB mstr_standard
J 2
(-1850 4700);
DISPLAY 0.787234 (-1850 4700);
PAINT MONO (-1850 4700);
DISPLAY INVISIBLE (-1850 4700);
FORCEPROP 1 LAST BODY_TYPE PLUMBING
J 2
(-1850 4650);
DISPLAY 1.234043 (-1850 4650);
PAINT GREEN (-1850 4650);
DISPLAY INVISIBLE (-1850 4650);
FORCEPROP 1 LAST HDL_TAP TRUE
J 2
(-2175 4575);
DISPLAY 1.234043 (-2175 4575);
PAINT GREEN (-2175 4575);
DISPLAY INVISIBLE (-2175 4575);
FORCEPROP 1 LAST PATH I50
J 2
(-1850 4700);
DISPLAY 0.936170 (-1850 4700);
PAINT GREEN (-1850 4700);
DISPLAY INVISIBLE (-1850 4700);
FORCEADD TAP..6
R 2
(-1850 4650);
FORCEPROP 3 LASTPIN (-1900 4650) SIG_NAME M_H_DQ<59>
J 0
(-1890 4660);
DISPLAY 0.659574 (-1890 4660);
PAINT MONO (-1890 4660);
DISPLAY INVISIBLE (-1890 4660);
FORCEPROP 1 LASTPIN (-1900 4650) BN 59
J 2
(-1850 4660);
DISPLAY 0.617021 (-1850 4660);
PAINT PINK (-1850 4660);
FORCEPROP 2 LAST CDS_LIB mstr_standard
J 2
(-1850 4650);
DISPLAY 0.787234 (-1850 4650);
PAINT MONO (-1850 4650);
DISPLAY INVISIBLE (-1850 4650);
FORCEPROP 1 LAST BODY_TYPE PLUMBING
J 2
(-1850 4600);
DISPLAY 1.234043 (-1850 4600);
PAINT GREEN (-1850 4600);
DISPLAY INVISIBLE (-1850 4600);
FORCEPROP 1 LAST HDL_TAP TRUE
J 2
(-2175 4525);
DISPLAY 1.234043 (-2175 4525);
PAINT GREEN (-2175 4525);
DISPLAY INVISIBLE (-2175 4525);
FORCEPROP 1 LAST PATH I51
J 2
(-1850 4650);
DISPLAY 0.936170 (-1850 4650);
PAINT GREEN (-1850 4650);
DISPLAY INVISIBLE (-1850 4650);
FORCEADD TAP..6
R 2
(-1850 4600);
FORCEPROP 3 LASTPIN (-1900 4600) SIG_NAME M_H_DQ<56>
J 0
(-1890 4610);
DISPLAY 0.659574 (-1890 4610);
PAINT MONO (-1890 4610);
DISPLAY INVISIBLE (-1890 4610);
FORCEPROP 1 LASTPIN (-1900 4600) BN 56
J 2
(-1850 4610);
DISPLAY 0.617021 (-1850 4610);
PAINT PINK (-1850 4610);
FORCEPROP 2 LAST CDS_LIB mstr_standard
J 2
(-1850 4600);
DISPLAY 0.787234 (-1850 4600);
PAINT MONO (-1850 4600);
DISPLAY INVISIBLE (-1850 4600);
FORCEPROP 1 LAST BODY_TYPE PLUMBING
J 2
(-1850 4550);
DISPLAY 1.234043 (-1850 4550);
PAINT GREEN (-1850 4550);
DISPLAY INVISIBLE (-1850 4550);
FORCEPROP 1 LAST HDL_TAP TRUE
J 2
(-2175 4475);
DISPLAY 1.234043 (-2175 4475);
PAINT GREEN (-2175 4475);
DISPLAY INVISIBLE (-2175 4475);
FORCEPROP 1 LAST PATH I52
J 2
(-1850 4600);
DISPLAY 0.936170 (-1850 4600);
PAINT GREEN (-1850 4600);
DISPLAY INVISIBLE (-1850 4600);
FORCEADD TAP..6
R 2
(-1850 4400);
FORCEPROP 3 LASTPIN (-1900 4400) SIG_NAME M_H_DQ<52>
J 0
(-1890 4410);
DISPLAY 0.659574 (-1890 4410);
PAINT MONO (-1890 4410);
DISPLAY INVISIBLE (-1890 4410);
FORCEPROP 1 LASTPIN (-1900 4400) BN 52
J 2
(-1850 4410);
DISPLAY 0.617021 (-1850 4410);
PAINT PINK (-1850 4410);
FORCEPROP 2 LAST CDS_LIB mstr_standard
J 2
(-1850 4400);
DISPLAY 0.787234 (-1850 4400);
PAINT MONO (-1850 4400);
DISPLAY INVISIBLE (-1850 4400);
FORCEPROP 1 LAST BODY_TYPE PLUMBING
J 2
(-1850 4350);
DISPLAY 1.234043 (-1850 4350);
PAINT GREEN (-1850 4350);
DISPLAY INVISIBLE (-1850 4350);
FORCEPROP 1 LAST HDL_TAP TRUE
J 2
(-2175 4275);
DISPLAY 1.234043 (-2175 4275);
PAINT GREEN (-2175 4275);
DISPLAY INVISIBLE (-2175 4275);
FORCEPROP 1 LAST PATH I53
J 2
(-1850 4400);
DISPLAY 0.936170 (-1850 4400);
PAINT GREEN (-1850 4400);
DISPLAY INVISIBLE (-1850 4400);
FORCEADD TAP..6
R 2
(-1850 4450);
FORCEPROP 3 LASTPIN (-1900 4450) SIG_NAME M_H_DQ<55>
J 0
(-1890 4460);
DISPLAY 0.659574 (-1890 4460);
PAINT MONO (-1890 4460);
DISPLAY INVISIBLE (-1890 4460);
FORCEPROP 1 LASTPIN (-1900 4450) BN 55
J 2
(-1850 4460);
DISPLAY 0.617021 (-1850 4460);
PAINT PINK (-1850 4460);
FORCEPROP 2 LAST CDS_LIB mstr_standard
J 2
(-1850 4450);
DISPLAY 0.787234 (-1850 4450);
PAINT MONO (-1850 4450);
DISPLAY INVISIBLE (-1850 4450);
FORCEPROP 1 LAST BODY_TYPE PLUMBING
J 2
(-1850 4400);
DISPLAY 1.234043 (-1850 4400);
PAINT GREEN (-1850 4400);
DISPLAY INVISIBLE (-1850 4400);
FORCEPROP 1 LAST HDL_TAP TRUE
J 2
(-2175 4325);
DISPLAY 1.234043 (-2175 4325);
PAINT GREEN (-2175 4325);
DISPLAY INVISIBLE (-2175 4325);
FORCEPROP 1 LAST PATH I54
J 2
(-1850 4450);
DISPLAY 0.936170 (-1850 4450);
PAINT GREEN (-1850 4450);
DISPLAY INVISIBLE (-1850 4450);
FORCEADD TAP..6
R 2
(-1850 4350);
FORCEPROP 3 LASTPIN (-1900 4350) SIG_NAME M_H_DQ<53>
J 0
(-1890 4360);
DISPLAY 0.659574 (-1890 4360);
PAINT MONO (-1890 4360);
DISPLAY INVISIBLE (-1890 4360);
FORCEPROP 1 LASTPIN (-1900 4350) BN 53
J 2
(-1850 4360);
DISPLAY 0.617021 (-1850 4360);
PAINT PINK (-1850 4360);
FORCEPROP 2 LAST CDS_LIB mstr_standard
J 2
(-1850 4350);
DISPLAY 0.787234 (-1850 4350);
PAINT MONO (-1850 4350);
DISPLAY INVISIBLE (-1850 4350);
FORCEPROP 1 LAST BODY_TYPE PLUMBING
J 2
(-1850 4300);
DISPLAY 1.234043 (-1850 4300);
PAINT GREEN (-1850 4300);
DISPLAY INVISIBLE (-1850 4300);
FORCEPROP 1 LAST HDL_TAP TRUE
J 2
(-2175 4225);
DISPLAY 1.234043 (-2175 4225);
PAINT GREEN (-2175 4225);
DISPLAY INVISIBLE (-2175 4225);
FORCEPROP 1 LAST PATH I55
J 2
(-1850 4350);
DISPLAY 0.936170 (-1850 4350);
PAINT GREEN (-1850 4350);
DISPLAY INVISIBLE (-1850 4350);
FORCEADD TAP..6
R 2
(-1850 4500);
FORCEPROP 3 LASTPIN (-1900 4500) SIG_NAME M_H_DQ<54>
J 0
(-1890 4510);
DISPLAY 0.659574 (-1890 4510);
PAINT MONO (-1890 4510);
DISPLAY INVISIBLE (-1890 4510);
FORCEPROP 1 LASTPIN (-1900 4500) BN 54
J 2
(-1850 4510);
DISPLAY 0.617021 (-1850 4510);
PAINT PINK (-1850 4510);
FORCEPROP 2 LAST CDS_LIB mstr_standard
J 2
(-1850 4500);
DISPLAY 0.787234 (-1850 4500);
PAINT MONO (-1850 4500);
DISPLAY INVISIBLE (-1850 4500);
FORCEPROP 1 LAST BODY_TYPE PLUMBING
J 2
(-1850 4450);
DISPLAY 1.234043 (-1850 4450);
PAINT GREEN (-1850 4450);
DISPLAY INVISIBLE (-1850 4450);
FORCEPROP 1 LAST HDL_TAP TRUE
J 2
(-2175 4375);
DISPLAY 1.234043 (-2175 4375);
PAINT GREEN (-2175 4375);
DISPLAY INVISIBLE (-2175 4375);
FORCEPROP 1 LAST PATH I56
J 2
(-1850 4500);
DISPLAY 0.936170 (-1850 4500);
PAINT GREEN (-1850 4500);
DISPLAY INVISIBLE (-1850 4500);
FORCEADD TAP..6
R 2
(-1850 4550);
FORCEPROP 3 LASTPIN (-1900 4550) SIG_NAME M_H_DQ<57>
J 0
(-1890 4560);
DISPLAY 0.659574 (-1890 4560);
PAINT MONO (-1890 4560);
DISPLAY INVISIBLE (-1890 4560);
FORCEPROP 1 LASTPIN (-1900 4550) BN 57
J 2
(-1850 4560);
DISPLAY 0.617021 (-1850 4560);
PAINT PINK (-1850 4560);
FORCEPROP 2 LAST CDS_LIB mstr_standard
J 2
(-1850 4550);
DISPLAY 0.787234 (-1850 4550);
PAINT MONO (-1850 4550);
DISPLAY INVISIBLE (-1850 4550);
FORCEPROP 1 LAST BODY_TYPE PLUMBING
J 2
(-1850 4500);
DISPLAY 1.234043 (-1850 4500);
PAINT GREEN (-1850 4500);
DISPLAY INVISIBLE (-1850 4500);
FORCEPROP 1 LAST HDL_TAP TRUE
J 2
(-2175 4425);
DISPLAY 1.234043 (-2175 4425);
PAINT GREEN (-2175 4425);
DISPLAY INVISIBLE (-2175 4425);
FORCEPROP 1 LAST PATH I57
J 2
(-1850 4550);
DISPLAY 0.936170 (-1850 4550);
PAINT GREEN (-1850 4550);
DISPLAY INVISIBLE (-1850 4550);
FORCEADD TAP..6
R 2
(-1850 4100);
FORCEPROP 3 LASTPIN (-1900 4100) SIG_NAME M_H_DQ<46>
J 0
(-1890 4110);
DISPLAY 0.659574 (-1890 4110);
PAINT MONO (-1890 4110);
DISPLAY INVISIBLE (-1890 4110);
FORCEPROP 1 LASTPIN (-1900 4100) BN 46
J 2
(-1850 4110);
DISPLAY 0.617021 (-1850 4110);
PAINT PINK (-1850 4110);
FORCEPROP 2 LAST CDS_LIB mstr_standard
J 2
(-1850 4100);
DISPLAY 0.787234 (-1850 4100);
PAINT MONO (-1850 4100);
DISPLAY INVISIBLE (-1850 4100);
FORCEPROP 1 LAST BODY_TYPE PLUMBING
J 2
(-1850 4050);
DISPLAY 1.234043 (-1850 4050);
PAINT GREEN (-1850 4050);
DISPLAY INVISIBLE (-1850 4050);
FORCEPROP 1 LAST HDL_TAP TRUE
J 2
(-2175 3975);
DISPLAY 1.234043 (-2175 3975);
PAINT GREEN (-2175 3975);
DISPLAY INVISIBLE (-2175 3975);
FORCEPROP 1 LAST PATH I58
J 2
(-1850 4100);
DISPLAY 0.936170 (-1850 4100);
PAINT GREEN (-1850 4100);
DISPLAY INVISIBLE (-1850 4100);
FORCEADD TAP..6
R 2
(-1850 4150);
FORCEPROP 3 LASTPIN (-1900 4150) SIG_NAME M_H_DQ<49>
J 0
(-1890 4160);
DISPLAY 0.659574 (-1890 4160);
PAINT MONO (-1890 4160);
DISPLAY INVISIBLE (-1890 4160);
FORCEPROP 1 LASTPIN (-1900 4150) BN 49
J 2
(-1850 4160);
DISPLAY 0.617021 (-1850 4160);
PAINT PINK (-1850 4160);
FORCEPROP 2 LAST CDS_LIB mstr_standard
J 2
(-1850 4150);
DISPLAY 0.787234 (-1850 4150);
PAINT MONO (-1850 4150);
DISPLAY INVISIBLE (-1850 4150);
FORCEPROP 1 LAST BODY_TYPE PLUMBING
J 2
(-1850 4100);
DISPLAY 1.234043 (-1850 4100);
PAINT GREEN (-1850 4100);
DISPLAY INVISIBLE (-1850 4100);
FORCEPROP 1 LAST HDL_TAP TRUE
J 2
(-2175 4025);
DISPLAY 1.234043 (-2175 4025);
PAINT GREEN (-2175 4025);
DISPLAY INVISIBLE (-2175 4025);
FORCEPROP 1 LAST PATH I59
J 2
(-1850 4150);
DISPLAY 0.936170 (-1850 4150);
PAINT GREEN (-1850 4150);
DISPLAY INVISIBLE (-1850 4150);
FORCEADD TAP..6
R 2
(850 4800);
FORCEPROP 3 LASTPIN (800 4800) SIG_NAME M_H_DQS_DN<14>
J 0
(810 4810);
DISPLAY 0.659574 (810 4810);
PAINT MONO (810 4810);
DISPLAY INVISIBLE (810 4810);
FORCEPROP 1 LASTPIN (800 4800) BN 14
J 2
(850 4810);
DISPLAY 0.617021 (850 4810);
PAINT PINK (850 4810);
FORCEPROP 2 LAST CDS_LIB mstr_standard
J 0
(850 4800);
DISPLAY 0.787234 (850 4800);
PAINT MONO (850 4800);
DISPLAY INVISIBLE (850 4800);
FORCEPROP 1 LAST BODY_TYPE PLUMBING
J 2
(850 4750);
DISPLAY 1.234043 (850 4750);
PAINT GREEN (850 4750);
DISPLAY INVISIBLE (850 4750);
FORCEPROP 1 LAST HDL_TAP TRUE
J 2
(525 4675);
DISPLAY 1.234043 (525 4675);
PAINT GREEN (525 4675);
DISPLAY INVISIBLE (525 4675);
FORCEPROP 1 LAST PATH I6
J 2
(850 4800);
DISPLAY 0.936170 (850 4800);
PAINT GREEN (850 4800);
DISPLAY INVISIBLE (850 4800);
FORCEADD TAP..6
R 2
(-1850 4050);
FORCEPROP 3 LASTPIN (-1900 4050) SIG_NAME M_H_DQ<47>
J 0
(-1890 4060);
DISPLAY 0.659574 (-1890 4060);
PAINT MONO (-1890 4060);
DISPLAY INVISIBLE (-1890 4060);
FORCEPROP 1 LASTPIN (-1900 4050) BN 47
J 2
(-1850 4060);
DISPLAY 0.617021 (-1850 4060);
PAINT PINK (-1850 4060);
FORCEPROP 2 LAST CDS_LIB mstr_standard
J 2
(-1850 4050);
DISPLAY 0.787234 (-1850 4050);
PAINT MONO (-1850 4050);
DISPLAY INVISIBLE (-1850 4050);
FORCEPROP 1 LAST BODY_TYPE PLUMBING
J 2
(-1850 4000);
DISPLAY 1.234043 (-1850 4000);
PAINT GREEN (-1850 4000);
DISPLAY INVISIBLE (-1850 4000);
FORCEPROP 1 LAST HDL_TAP TRUE
J 2
(-2175 3925);
DISPLAY 1.234043 (-2175 3925);
PAINT GREEN (-2175 3925);
DISPLAY INVISIBLE (-2175 3925);
FORCEPROP 1 LAST PATH I60
J 2
(-1850 4050);
DISPLAY 0.936170 (-1850 4050);
PAINT GREEN (-1850 4050);
DISPLAY INVISIBLE (-1850 4050);
FORCEADD TAP..6
R 2
(-1850 4200);
FORCEPROP 3 LASTPIN (-1900 4200) SIG_NAME M_H_DQ<48>
J 0
(-1890 4210);
DISPLAY 0.659574 (-1890 4210);
PAINT MONO (-1890 4210);
DISPLAY INVISIBLE (-1890 4210);
FORCEPROP 1 LASTPIN (-1900 4200) BN 48
J 2
(-1850 4210);
DISPLAY 0.617021 (-1850 4210);
PAINT PINK (-1850 4210);
FORCEPROP 2 LAST CDS_LIB mstr_standard
J 2
(-1850 4200);
DISPLAY 0.787234 (-1850 4200);
PAINT MONO (-1850 4200);
DISPLAY INVISIBLE (-1850 4200);
FORCEPROP 1 LAST BODY_TYPE PLUMBING
J 2
(-1850 4150);
DISPLAY 1.234043 (-1850 4150);
PAINT GREEN (-1850 4150);
DISPLAY INVISIBLE (-1850 4150);
FORCEPROP 1 LAST HDL_TAP TRUE
J 2
(-2175 4075);
DISPLAY 1.234043 (-2175 4075);
PAINT GREEN (-2175 4075);
DISPLAY INVISIBLE (-2175 4075);
FORCEPROP 1 LAST PATH I61
J 2
(-1850 4200);
DISPLAY 0.936170 (-1850 4200);
PAINT GREEN (-1850 4200);
DISPLAY INVISIBLE (-1850 4200);
FORCEADD TAP..6
R 2
(-1850 4250);
FORCEPROP 3 LASTPIN (-1900 4250) SIG_NAME M_H_DQ<51>
J 0
(-1890 4260);
DISPLAY 0.659574 (-1890 4260);
PAINT MONO (-1890 4260);
DISPLAY INVISIBLE (-1890 4260);
FORCEPROP 1 LASTPIN (-1900 4250) BN 51
J 2
(-1850 4260);
DISPLAY 0.617021 (-1850 4260);
PAINT PINK (-1850 4260);
FORCEPROP 2 LAST CDS_LIB mstr_standard
J 2
(-1850 4250);
DISPLAY 0.787234 (-1850 4250);
PAINT MONO (-1850 4250);
DISPLAY INVISIBLE (-1850 4250);
FORCEPROP 1 LAST BODY_TYPE PLUMBING
J 2
(-1850 4200);
DISPLAY 1.234043 (-1850 4200);
PAINT GREEN (-1850 4200);
DISPLAY INVISIBLE (-1850 4200);
FORCEPROP 1 LAST HDL_TAP TRUE
J 2
(-2175 4125);
DISPLAY 1.234043 (-2175 4125);
PAINT GREEN (-2175 4125);
DISPLAY INVISIBLE (-2175 4125);
FORCEPROP 1 LAST PATH I62
J 2
(-1850 4250);
DISPLAY 0.936170 (-1850 4250);
PAINT GREEN (-1850 4250);
DISPLAY INVISIBLE (-1850 4250);
FORCEADD TAP..6
R 2
(-1850 4300);
FORCEPROP 3 LASTPIN (-1900 4300) SIG_NAME M_H_DQ<50>
J 0
(-1890 4310);
DISPLAY 0.659574 (-1890 4310);
PAINT MONO (-1890 4310);
DISPLAY INVISIBLE (-1890 4310);
FORCEPROP 1 LASTPIN (-1900 4300) BN 50
J 2
(-1850 4310);
DISPLAY 0.617021 (-1850 4310);
PAINT PINK (-1850 4310);
FORCEPROP 2 LAST CDS_LIB mstr_standard
J 2
(-1850 4300);
DISPLAY 0.787234 (-1850 4300);
PAINT MONO (-1850 4300);
DISPLAY INVISIBLE (-1850 4300);
FORCEPROP 1 LAST BODY_TYPE PLUMBING
J 2
(-1850 4250);
DISPLAY 1.234043 (-1850 4250);
PAINT GREEN (-1850 4250);
DISPLAY INVISIBLE (-1850 4250);
FORCEPROP 1 LAST HDL_TAP TRUE
J 2
(-2175 4175);
DISPLAY 1.234043 (-2175 4175);
PAINT GREEN (-2175 4175);
DISPLAY INVISIBLE (-2175 4175);
FORCEPROP 1 LAST PATH I63
J 2
(-1850 4300);
DISPLAY 0.936170 (-1850 4300);
PAINT GREEN (-1850 4300);
DISPLAY INVISIBLE (-1850 4300);
FORCEADD SCONN288_H44441004..2
(-50 4300);
FORCEPROP 1 LAST LOCATION J1G2
J 0
(-450 5400);
DISPLAY 0.617021 (-450 5400);
PAINT AQUA (-450 5400);
FORCEPROP 1 LAST PART_NUMBER H44441-004
J 0
(-450 3200);
DISPLAY 0.617021 (-450 3200);
PAINT BLUE (-450 3200);
FORCEPROP 1 LAST MATERIAL SCONN
J 0
(-450 5350);
DISPLAY 0.617021 (-450 5350);
PAINT SKYBLUE (-450 5350);
FORCEPROP 2 LASTPIN (400 5150) $PN 51
J 0
(410 5160);
DISPLAY 0.617021 (410 5160);
PAINT ORANGE (410 5160);
FORCEPROP 2 LASTPIN (400 5100) $PN 52
J 0
(410 5110);
DISPLAY 0.617021 (410 5110);
PAINT ORANGE (410 5110);
FORCEPROP 2 LASTPIN (400 5050) $PN 132
J 0
(410 5060);
DISPLAY 0.617021 (410 5060);
PAINT ORANGE (410 5060);
FORCEPROP 2 LASTPIN (400 5000) $PN 133
J 0
(410 5010);
DISPLAY 0.617021 (410 5010);
PAINT ORANGE (410 5010);
FORCEPROP 2 LASTPIN (400 4950) $PN 121
J 0
(410 4960);
DISPLAY 0.617021 (410 4960);
PAINT ORANGE (410 4960);
FORCEPROP 2 LASTPIN (400 4900) $PN 122
J 0
(410 4910);
DISPLAY 0.617021 (410 4910);
PAINT ORANGE (410 4910);
FORCEPROP 2 LASTPIN (400 4850) $PN 110
J 0
(410 4860);
DISPLAY 0.617021 (410 4860);
PAINT ORANGE (410 4860);
FORCEPROP 2 LASTPIN (400 4800) $PN 111
J 0
(410 4810);
DISPLAY 0.617021 (410 4810);
PAINT ORANGE (410 4810);
FORCEPROP 2 LASTPIN (400 4750) $PN 99
J 0
(410 4760);
DISPLAY 0.617021 (410 4760);
PAINT ORANGE (410 4760);
FORCEPROP 2 LASTPIN (400 4700) $PN 100
J 0
(410 4710);
DISPLAY 0.617021 (410 4710);
PAINT ORANGE (410 4710);
FORCEPROP 2 LASTPIN (400 4650) $PN 40
J 0
(410 4660);
DISPLAY 0.617021 (410 4660);
PAINT ORANGE (410 4660);
FORCEPROP 2 LASTPIN (400 4600) $PN 41
J 0
(410 4610);
DISPLAY 0.617021 (410 4610);
PAINT ORANGE (410 4610);
FORCEPROP 2 LASTPIN (400 4550) $PN 29
J 0
(410 4560);
DISPLAY 0.617021 (410 4560);
PAINT ORANGE (410 4560);
FORCEPROP 2 LASTPIN (400 4500) $PN 30
J 0
(410 4510);
DISPLAY 0.617021 (410 4510);
PAINT ORANGE (410 4510);
FORCEPROP 2 LASTPIN (400 4450) $PN 18
J 0
(410 4460);
DISPLAY 0.617021 (410 4460);
PAINT ORANGE (410 4460);
FORCEPROP 2 LASTPIN (400 4400) $PN 19
J 0
(410 4410);
DISPLAY 0.617021 (410 4410);
PAINT ORANGE (410 4410);
FORCEPROP 2 LASTPIN (400 4350) $PN 7
J 0
(410 4360);
DISPLAY 0.617021 (410 4360);
PAINT ORANGE (410 4360);
FORCEPROP 2 LASTPIN (400 4300) $PN 8
J 0
(410 4310);
DISPLAY 0.617021 (410 4310);
PAINT ORANGE (410 4310);
FORCEPROP 2 LASTPIN (400 4250) $PN 197
J 0
(410 4260);
DISPLAY 0.617021 (410 4260);
PAINT ORANGE (410 4260);
FORCEPROP 2 LASTPIN (400 4200) $PN 196
J 0
(410 4210);
DISPLAY 0.617021 (410 4210);
PAINT ORANGE (410 4210);
FORCEPROP 2 LASTPIN (400 4150) $PN 278
J 0
(410 4160);
DISPLAY 0.617021 (410 4160);
PAINT ORANGE (410 4160);
FORCEPROP 2 LASTPIN (400 4100) $PN 277
J 0
(410 4110);
DISPLAY 0.617021 (410 4110);
PAINT ORANGE (410 4110);
FORCEPROP 2 LASTPIN (400 4050) $PN 267
J 0
(410 4060);
DISPLAY 0.617021 (410 4060);
PAINT ORANGE (410 4060);
FORCEPROP 2 LASTPIN (400 4000) $PN 266
J 0
(410 4010);
DISPLAY 0.617021 (410 4010);
PAINT ORANGE (410 4010);
FORCEPROP 2 LASTPIN (400 3900) $PN 255
J 0
(410 3910);
DISPLAY 0.617021 (410 3910);
PAINT ORANGE (410 3910);
FORCEPROP 2 LASTPIN (400 3850) $PN 245
J 0
(410 3860);
DISPLAY 0.617021 (410 3860);
PAINT ORANGE (410 3860);
FORCEPROP 2 LASTPIN (400 3800) $PN 244
J 0
(410 3810);
DISPLAY 0.617021 (410 3810);
PAINT ORANGE (410 3810);
FORCEPROP 2 LASTPIN (400 3750) $PN 186
J 0
(410 3760);
DISPLAY 0.617021 (410 3760);
PAINT ORANGE (410 3760);
FORCEPROP 2 LASTPIN (400 3700) $PN 185
J 0
(410 3710);
DISPLAY 0.617021 (410 3710);
PAINT ORANGE (410 3710);
FORCEPROP 2 LASTPIN (400 3600) $PN 174
J 0
(410 3610);
DISPLAY 0.617021 (410 3610);
PAINT ORANGE (410 3610);
FORCEPROP 2 LASTPIN (400 3500) $PN 163
J 0
(410 3510);
DISPLAY 0.617021 (410 3510);
PAINT ORANGE (410 3510);
FORCEPROP 2 LASTPIN (400 3450) $PN 153
J 0
(410 3460);
DISPLAY 0.617021 (410 3460);
PAINT ORANGE (410 3460);
FORCEPROP 2 LASTPIN (400 3400) $PN 152
J 0
(410 3410);
DISPLAY 0.617021 (410 3410);
PAINT ORANGE (410 3410);
FORCEPROP 2 LASTPIN (400 3950) $PN 256
J 0
(410 3960);
DISPLAY 0.617021 (410 3960);
PAINT ORANGE (410 3960);
FORCEPROP 2 LASTPIN (400 3650) $PN 175
J 0
(410 3660);
DISPLAY 0.617021 (410 3660);
PAINT ORANGE (410 3660);
FORCEPROP 2 LASTPIN (400 3550) $PN 164
J 0
(410 3560);
DISPLAY 0.617021 (410 3560);
PAINT ORANGE (410 3560);
FORCEPROP 1 LAST PACK_TYPE PIP
J 0
(-450 5450);
PAINT SKYBLUE (-450 5450);
DISPLAY INVISIBLE (-450 5450);
FORCEPROP 2 LAST BOM_COST MEM
J 0
(-50 4300);
PAINT ORANGE (-50 4300);
DISPLAY INVISIBLE (-50 4300);
FORCEPROP 2 LAST CDS_LIB mstr_sconn
J 0
(-50 4300);
PAINT ORANGE (-50 4300);
DISPLAY INVISIBLE (-50 4300);
FORCEPROP 2 LAST SEC_TYPE PIP
J 0
(-450 5450);
DISPLAY 1.021277 (-450 5450);
PAINT ORANGE (-450 5450);
DISPLAY INVISIBLE (-450 5450);
FORCEPROP 2 LAST SEC 2
J 0
(-450 5450);
DISPLAY 0.680851 (-450 5450);
PAINT MONO (-450 5450);
DISPLAY INVISIBLE (-450 5450);
FORCEPROP 2 LAST CDS_LOCATION J1G2
J 0
(-450 5400);
DISPLAY 0.617021 (-450 5400);
PAINT AQUA (-450 5400);
DISPLAY INVISIBLE (-450 5400);
FORCEPROP 1 LAST PATH I64
J 0
(-50 5350);
PAINT GREEN (-50 5350);
DISPLAY INVISIBLE (-50 5350);
FORCEPROP 2 LAST ROOM DDR4_CH_H
J 0
(-50 4300);
PAINT ORANGE (-50 4300);
DISPLAY INVISIBLE (-50 4300);
FORCEADD TAP..6
R 2
(-1850 3900);
FORCEPROP 3 LASTPIN (-1900 3900) SIG_NAME M_H_DQ<42>
J 0
(-1890 3910);
DISPLAY 0.659574 (-1890 3910);
PAINT MONO (-1890 3910);
DISPLAY INVISIBLE (-1890 3910);
FORCEPROP 1 LASTPIN (-1900 3900) BN 42
J 2
(-1850 3910);
DISPLAY 0.617021 (-1850 3910);
PAINT PINK (-1850 3910);
FORCEPROP 2 LAST CDS_LIB mstr_standard
J 2
(-1850 3900);
DISPLAY 0.787234 (-1850 3900);
PAINT MONO (-1850 3900);
DISPLAY INVISIBLE (-1850 3900);
FORCEPROP 1 LAST BODY_TYPE PLUMBING
J 2
(-1850 3850);
DISPLAY 1.234043 (-1850 3850);
PAINT GREEN (-1850 3850);
DISPLAY INVISIBLE (-1850 3850);
FORCEPROP 1 LAST HDL_TAP TRUE
J 2
(-2175 3775);
DISPLAY 1.234043 (-2175 3775);
PAINT GREEN (-2175 3775);
DISPLAY INVISIBLE (-2175 3775);
FORCEPROP 1 LAST PATH I65
J 2
(-1850 3900);
DISPLAY 0.936170 (-1850 3900);
PAINT GREEN (-1850 3900);
DISPLAY INVISIBLE (-1850 3900);
FORCEADD TAP..6
R 2
(-1850 3850);
FORCEPROP 3 LASTPIN (-1900 3850) SIG_NAME M_H_DQ<43>
J 0
(-1890 3860);
DISPLAY 0.659574 (-1890 3860);
PAINT MONO (-1890 3860);
DISPLAY INVISIBLE (-1890 3860);
FORCEPROP 1 LASTPIN (-1900 3850) BN 43
J 2
(-1850 3860);
DISPLAY 0.617021 (-1850 3860);
PAINT PINK (-1850 3860);
FORCEPROP 2 LAST CDS_LIB mstr_standard
J 2
(-1850 3850);
DISPLAY 0.787234 (-1850 3850);
PAINT MONO (-1850 3850);
DISPLAY INVISIBLE (-1850 3850);
FORCEPROP 1 LAST BODY_TYPE PLUMBING
J 2
(-1850 3800);
DISPLAY 1.234043 (-1850 3800);
PAINT GREEN (-1850 3800);
DISPLAY INVISIBLE (-1850 3800);
FORCEPROP 1 LAST HDL_TAP TRUE
J 2
(-2175 3725);
DISPLAY 1.234043 (-2175 3725);
PAINT GREEN (-2175 3725);
DISPLAY INVISIBLE (-2175 3725);
FORCEPROP 1 LAST PATH I66
J 2
(-1850 3850);
DISPLAY 0.936170 (-1850 3850);
PAINT GREEN (-1850 3850);
DISPLAY INVISIBLE (-1850 3850);
FORCEADD TAP..6
R 2
(-1850 3800);
FORCEPROP 3 LASTPIN (-1900 3800) SIG_NAME M_H_DQ<40>
J 0
(-1890 3810);
DISPLAY 0.659574 (-1890 3810);
PAINT MONO (-1890 3810);
DISPLAY INVISIBLE (-1890 3810);
FORCEPROP 1 LASTPIN (-1900 3800) BN 40
J 2
(-1850 3810);
DISPLAY 0.617021 (-1850 3810);
PAINT PINK (-1850 3810);
FORCEPROP 2 LAST CDS_LIB mstr_standard
J 2
(-1850 3800);
DISPLAY 0.787234 (-1850 3800);
PAINT MONO (-1850 3800);
DISPLAY INVISIBLE (-1850 3800);
FORCEPROP 1 LAST BODY_TYPE PLUMBING
J 2
(-1850 3750);
DISPLAY 1.234043 (-1850 3750);
PAINT GREEN (-1850 3750);
DISPLAY INVISIBLE (-1850 3750);
FORCEPROP 1 LAST HDL_TAP TRUE
J 2
(-2175 3675);
DISPLAY 1.234043 (-2175 3675);
PAINT GREEN (-2175 3675);
DISPLAY INVISIBLE (-2175 3675);
FORCEPROP 1 LAST PATH I67
J 2
(-1850 3800);
DISPLAY 0.936170 (-1850 3800);
PAINT GREEN (-1850 3800);
DISPLAY INVISIBLE (-1850 3800);
FORCEADD TAP..6
R 2
(-1850 3950);
FORCEPROP 3 LASTPIN (-1900 3950) SIG_NAME M_H_DQ<45>
J 0
(-1890 3960);
DISPLAY 0.659574 (-1890 3960);
PAINT MONO (-1890 3960);
DISPLAY INVISIBLE (-1890 3960);
FORCEPROP 1 LASTPIN (-1900 3950) BN 45
J 2
(-1850 3960);
DISPLAY 0.617021 (-1850 3960);
PAINT PINK (-1850 3960);
FORCEPROP 2 LAST CDS_LIB mstr_standard
J 2
(-1850 3950);
DISPLAY 0.787234 (-1850 3950);
PAINT MONO (-1850 3950);
DISPLAY INVISIBLE (-1850 3950);
FORCEPROP 1 LAST BODY_TYPE PLUMBING
J 2
(-1850 3900);
DISPLAY 1.234043 (-1850 3900);
PAINT GREEN (-1850 3900);
DISPLAY INVISIBLE (-1850 3900);
FORCEPROP 1 LAST HDL_TAP TRUE
J 2
(-2175 3825);
DISPLAY 1.234043 (-2175 3825);
PAINT GREEN (-2175 3825);
DISPLAY INVISIBLE (-2175 3825);
FORCEPROP 1 LAST PATH I68
J 2
(-1850 3950);
DISPLAY 0.936170 (-1850 3950);
PAINT GREEN (-1850 3950);
DISPLAY INVISIBLE (-1850 3950);
FORCEADD TAP..6
R 2
(-1850 4000);
FORCEPROP 3 LASTPIN (-1900 4000) SIG_NAME M_H_DQ<44>
J 0
(-1890 4010);
DISPLAY 0.659574 (-1890 4010);
PAINT MONO (-1890 4010);
DISPLAY INVISIBLE (-1890 4010);
FORCEPROP 1 LASTPIN (-1900 4000) BN 44
J 2
(-1850 4010);
DISPLAY 0.617021 (-1850 4010);
PAINT PINK (-1850 4010);
FORCEPROP 2 LAST CDS_LIB mstr_standard
J 2
(-1850 4000);
DISPLAY 0.787234 (-1850 4000);
PAINT MONO (-1850 4000);
DISPLAY INVISIBLE (-1850 4000);
FORCEPROP 1 LAST BODY_TYPE PLUMBING
J 2
(-1850 3950);
DISPLAY 1.234043 (-1850 3950);
PAINT GREEN (-1850 3950);
DISPLAY INVISIBLE (-1850 3950);
FORCEPROP 1 LAST HDL_TAP TRUE
J 2
(-2175 3875);
DISPLAY 1.234043 (-2175 3875);
PAINT GREEN (-2175 3875);
DISPLAY INVISIBLE (-2175 3875);
FORCEPROP 1 LAST PATH I69
J 2
(-1850 4000);
DISPLAY 0.936170 (-1850 4000);
PAINT GREEN (-1850 4000);
DISPLAY INVISIBLE (-1850 4000);
FORCEADD TAP..6
R 2
(850 4700);
FORCEPROP 3 LASTPIN (800 4700) SIG_NAME M_H_DQS_DN<13>
J 0
(810 4710);
DISPLAY 0.659574 (810 4710);
PAINT MONO (810 4710);
DISPLAY INVISIBLE (810 4710);
FORCEPROP 1 LASTPIN (800 4700) BN 13
J 2
(850 4710);
DISPLAY 0.617021 (850 4710);
PAINT PINK (850 4710);
FORCEPROP 2 LAST CDS_LIB mstr_standard
J 0
(850 4700);
DISPLAY 0.787234 (850 4700);
PAINT MONO (850 4700);
DISPLAY INVISIBLE (850 4700);
FORCEPROP 1 LAST BODY_TYPE PLUMBING
J 2
(850 4650);
DISPLAY 1.234043 (850 4650);
PAINT GREEN (850 4650);
DISPLAY INVISIBLE (850 4650);
FORCEPROP 1 LAST HDL_TAP TRUE
J 2
(525 4575);
DISPLAY 1.234043 (525 4575);
PAINT GREEN (525 4575);
DISPLAY INVISIBLE (525 4575);
FORCEPROP 1 LAST PATH I7
J 2
(850 4700);
DISPLAY 0.936170 (850 4700);
PAINT GREEN (850 4700);
DISPLAY INVISIBLE (850 4700);
FORCEADD TAP..6
R 2
(-1850 3650);
FORCEPROP 3 LASTPIN (-1900 3650) SIG_NAME M_H_DQ<39>
J 0
(-1890 3660);
DISPLAY 0.659574 (-1890 3660);
PAINT MONO (-1890 3660);
DISPLAY INVISIBLE (-1890 3660);
FORCEPROP 1 LASTPIN (-1900 3650) BN 39
J 2
(-1850 3660);
DISPLAY 0.617021 (-1850 3660);
PAINT PINK (-1850 3660);
FORCEPROP 2 LAST CDS_LIB mstr_standard
J 2
(-1850 3650);
DISPLAY 0.787234 (-1850 3650);
PAINT MONO (-1850 3650);
DISPLAY INVISIBLE (-1850 3650);
FORCEPROP 1 LAST BODY_TYPE PLUMBING
J 2
(-1850 3600);
DISPLAY 1.234043 (-1850 3600);
PAINT GREEN (-1850 3600);
DISPLAY INVISIBLE (-1850 3600);
FORCEPROP 1 LAST HDL_TAP TRUE
J 2
(-2175 3525);
DISPLAY 1.234043 (-2175 3525);
PAINT GREEN (-2175 3525);
DISPLAY INVISIBLE (-2175 3525);
FORCEPROP 1 LAST PATH I70
J 2
(-1850 3650);
DISPLAY 0.936170 (-1850 3650);
PAINT GREEN (-1850 3650);
DISPLAY INVISIBLE (-1850 3650);
FORCEADD TAP..6
R 2
(-1850 3600);
FORCEPROP 3 LASTPIN (-1900 3600) SIG_NAME M_H_DQ<36>
J 0
(-1890 3610);
DISPLAY 0.659574 (-1890 3610);
PAINT MONO (-1890 3610);
DISPLAY INVISIBLE (-1890 3610);
FORCEPROP 1 LASTPIN (-1900 3600) BN 36
J 2
(-1850 3610);
DISPLAY 0.617021 (-1850 3610);
PAINT PINK (-1850 3610);
FORCEPROP 2 LAST CDS_LIB mstr_standard
J 2
(-1850 3600);
DISPLAY 0.787234 (-1850 3600);
PAINT MONO (-1850 3600);
DISPLAY INVISIBLE (-1850 3600);
FORCEPROP 1 LAST BODY_TYPE PLUMBING
J 2
(-1850 3550);
DISPLAY 1.234043 (-1850 3550);
PAINT GREEN (-1850 3550);
DISPLAY INVISIBLE (-1850 3550);
FORCEPROP 1 LAST HDL_TAP TRUE
J 2
(-2175 3475);
DISPLAY 1.234043 (-2175 3475);
PAINT GREEN (-2175 3475);
DISPLAY INVISIBLE (-2175 3475);
FORCEPROP 1 LAST PATH I71
J 2
(-1850 3600);
DISPLAY 0.936170 (-1850 3600);
PAINT GREEN (-1850 3600);
DISPLAY INVISIBLE (-1850 3600);
FORCEADD TAP..6
R 2
(-1850 3550);
FORCEPROP 3 LASTPIN (-1900 3550) SIG_NAME M_H_DQ<37>
J 0
(-1890 3560);
DISPLAY 0.659574 (-1890 3560);
PAINT MONO (-1890 3560);
DISPLAY INVISIBLE (-1890 3560);
FORCEPROP 1 LASTPIN (-1900 3550) BN 37
J 2
(-1850 3560);
DISPLAY 0.617021 (-1850 3560);
PAINT PINK (-1850 3560);
FORCEPROP 2 LAST CDS_LIB mstr_standard
J 2
(-1850 3550);
DISPLAY 0.787234 (-1850 3550);
PAINT MONO (-1850 3550);
DISPLAY INVISIBLE (-1850 3550);
FORCEPROP 1 LAST BODY_TYPE PLUMBING
J 2
(-1850 3500);
DISPLAY 1.234043 (-1850 3500);
PAINT GREEN (-1850 3500);
DISPLAY INVISIBLE (-1850 3500);
FORCEPROP 1 LAST HDL_TAP TRUE
J 2
(-2175 3425);
DISPLAY 1.234043 (-2175 3425);
PAINT GREEN (-2175 3425);
DISPLAY INVISIBLE (-2175 3425);
FORCEPROP 1 LAST PATH I72
J 2
(-1850 3550);
DISPLAY 0.936170 (-1850 3550);
PAINT GREEN (-1850 3550);
DISPLAY INVISIBLE (-1850 3550);
FORCEADD TAP..6
R 2
(-1850 3750);
FORCEPROP 3 LASTPIN (-1900 3750) SIG_NAME M_H_DQ<41>
J 0
(-1890 3760);
DISPLAY 0.659574 (-1890 3760);
PAINT MONO (-1890 3760);
DISPLAY INVISIBLE (-1890 3760);
FORCEPROP 1 LASTPIN (-1900 3750) BN 41
J 2
(-1850 3760);
DISPLAY 0.617021 (-1850 3760);
PAINT PINK (-1850 3760);
FORCEPROP 2 LAST CDS_LIB mstr_standard
J 2
(-1850 3750);
DISPLAY 0.787234 (-1850 3750);
PAINT MONO (-1850 3750);
DISPLAY INVISIBLE (-1850 3750);
FORCEPROP 1 LAST BODY_TYPE PLUMBING
J 2
(-1850 3700);
DISPLAY 1.234043 (-1850 3700);
PAINT GREEN (-1850 3700);
DISPLAY INVISIBLE (-1850 3700);
FORCEPROP 1 LAST HDL_TAP TRUE
J 2
(-2175 3625);
DISPLAY 1.234043 (-2175 3625);
PAINT GREEN (-2175 3625);
DISPLAY INVISIBLE (-2175 3625);
FORCEPROP 1 LAST PATH I73
J 2
(-1850 3750);
DISPLAY 0.936170 (-1850 3750);
PAINT GREEN (-1850 3750);
DISPLAY INVISIBLE (-1850 3750);
FORCEADD TAP..6
R 2
(-1850 3700);
FORCEPROP 3 LASTPIN (-1900 3700) SIG_NAME M_H_DQ<38>
J 0
(-1890 3710);
DISPLAY 0.659574 (-1890 3710);
PAINT MONO (-1890 3710);
DISPLAY INVISIBLE (-1890 3710);
FORCEPROP 1 LASTPIN (-1900 3700) BN 38
J 2
(-1850 3710);
DISPLAY 0.617021 (-1850 3710);
PAINT PINK (-1850 3710);
FORCEPROP 2 LAST CDS_LIB mstr_standard
J 2
(-1850 3700);
DISPLAY 0.787234 (-1850 3700);
PAINT MONO (-1850 3700);
DISPLAY INVISIBLE (-1850 3700);
FORCEPROP 1 LAST BODY_TYPE PLUMBING
J 2
(-1850 3650);
DISPLAY 1.234043 (-1850 3650);
PAINT GREEN (-1850 3650);
DISPLAY INVISIBLE (-1850 3650);
FORCEPROP 1 LAST HDL_TAP TRUE
J 2
(-2175 3575);
DISPLAY 1.234043 (-2175 3575);
PAINT GREEN (-2175 3575);
DISPLAY INVISIBLE (-2175 3575);
FORCEPROP 1 LAST PATH I74
J 2
(-1850 3700);
DISPLAY 0.936170 (-1850 3700);
PAINT GREEN (-1850 3700);
DISPLAY INVISIBLE (-1850 3700);
FORCEADD TAP..6
R 2
(-1850 3400);
FORCEPROP 3 LASTPIN (-1900 3400) SIG_NAME M_H_DQ<32>
J 0
(-1890 3410);
DISPLAY 0.659574 (-1890 3410);
PAINT MONO (-1890 3410);
DISPLAY INVISIBLE (-1890 3410);
FORCEPROP 1 LASTPIN (-1900 3400) BN 32
J 2
(-1850 3410);
DISPLAY 0.617021 (-1850 3410);
PAINT PINK (-1850 3410);
FORCEPROP 2 LAST CDS_LIB mstr_standard
J 2
(-1850 3400);
DISPLAY 0.787234 (-1850 3400);
PAINT MONO (-1850 3400);
DISPLAY INVISIBLE (-1850 3400);
FORCEPROP 1 LAST BODY_TYPE PLUMBING
J 2
(-1850 3350);
DISPLAY 1.234043 (-1850 3350);
PAINT GREEN (-1850 3350);
DISPLAY INVISIBLE (-1850 3350);
FORCEPROP 1 LAST HDL_TAP TRUE
J 2
(-2175 3275);
DISPLAY 1.234043 (-2175 3275);
PAINT GREEN (-2175 3275);
DISPLAY INVISIBLE (-2175 3275);
FORCEPROP 1 LAST PATH I75
J 2
(-1850 3400);
DISPLAY 0.936170 (-1850 3400);
PAINT GREEN (-1850 3400);
DISPLAY INVISIBLE (-1850 3400);
FORCEADD TAP..6
R 2
(-1850 3350);
FORCEPROP 3 LASTPIN (-1900 3350) SIG_NAME M_H_DQ<33>
J 0
(-1890 3360);
DISPLAY 0.659574 (-1890 3360);
PAINT MONO (-1890 3360);
DISPLAY INVISIBLE (-1890 3360);
FORCEPROP 1 LASTPIN (-1900 3350) BN 33
J 2
(-1850 3360);
DISPLAY 0.617021 (-1850 3360);
PAINT PINK (-1850 3360);
FORCEPROP 2 LAST CDS_LIB mstr_standard
J 2
(-1850 3350);
DISPLAY 0.787234 (-1850 3350);
PAINT MONO (-1850 3350);
DISPLAY INVISIBLE (-1850 3350);
FORCEPROP 1 LAST BODY_TYPE PLUMBING
J 2
(-1850 3300);
DISPLAY 1.234043 (-1850 3300);
PAINT GREEN (-1850 3300);
DISPLAY INVISIBLE (-1850 3300);
FORCEPROP 1 LAST HDL_TAP TRUE
J 2
(-2175 3225);
DISPLAY 1.234043 (-2175 3225);
PAINT GREEN (-2175 3225);
DISPLAY INVISIBLE (-2175 3225);
FORCEPROP 1 LAST PATH I76
J 2
(-1850 3350);
DISPLAY 0.936170 (-1850 3350);
PAINT GREEN (-1850 3350);
DISPLAY INVISIBLE (-1850 3350);
FORCEADD TAP..6
R 2
(-1850 3300);
FORCEPROP 3 LASTPIN (-1900 3300) SIG_NAME M_H_DQ<30>
J 0
(-1890 3310);
DISPLAY 0.659574 (-1890 3310);
PAINT MONO (-1890 3310);
DISPLAY INVISIBLE (-1890 3310);
FORCEPROP 1 LASTPIN (-1900 3300) BN 30
J 2
(-1850 3310);
DISPLAY 0.617021 (-1850 3310);
PAINT PINK (-1850 3310);
FORCEPROP 2 LAST CDS_LIB mstr_standard
J 2
(-1850 3300);
DISPLAY 0.787234 (-1850 3300);
PAINT MONO (-1850 3300);
DISPLAY INVISIBLE (-1850 3300);
FORCEPROP 1 LAST BODY_TYPE PLUMBING
J 2
(-1850 3250);
DISPLAY 1.234043 (-1850 3250);
PAINT GREEN (-1850 3250);
DISPLAY INVISIBLE (-1850 3250);
FORCEPROP 1 LAST HDL_TAP TRUE
J 2
(-2175 3175);
DISPLAY 1.234043 (-2175 3175);
PAINT GREEN (-2175 3175);
DISPLAY INVISIBLE (-2175 3175);
FORCEPROP 1 LAST PATH I77
J 2
(-1850 3300);
DISPLAY 0.936170 (-1850 3300);
PAINT GREEN (-1850 3300);
DISPLAY INVISIBLE (-1850 3300);
FORCEADD TAP..6
R 2
(-1850 3500);
FORCEPROP 3 LASTPIN (-1900 3500) SIG_NAME M_H_DQ<34>
J 0
(-1890 3510);
DISPLAY 0.659574 (-1890 3510);
PAINT MONO (-1890 3510);
DISPLAY INVISIBLE (-1890 3510);
FORCEPROP 1 LASTPIN (-1900 3500) BN 34
J 2
(-1850 3510);
DISPLAY 0.617021 (-1850 3510);
PAINT PINK (-1850 3510);
FORCEPROP 2 LAST CDS_LIB mstr_standard
J 2
(-1850 3500);
DISPLAY 0.787234 (-1850 3500);
PAINT MONO (-1850 3500);
DISPLAY INVISIBLE (-1850 3500);
FORCEPROP 1 LAST BODY_TYPE PLUMBING
J 2
(-1850 3450);
DISPLAY 1.234043 (-1850 3450);
PAINT GREEN (-1850 3450);
DISPLAY INVISIBLE (-1850 3450);
FORCEPROP 1 LAST HDL_TAP TRUE
J 2
(-2175 3375);
DISPLAY 1.234043 (-2175 3375);
PAINT GREEN (-2175 3375);
DISPLAY INVISIBLE (-2175 3375);
FORCEPROP 1 LAST PATH I78
J 2
(-1850 3500);
DISPLAY 0.936170 (-1850 3500);
PAINT GREEN (-1850 3500);
DISPLAY INVISIBLE (-1850 3500);
FORCEADD TAP..6
R 2
(-1850 3450);
FORCEPROP 3 LASTPIN (-1900 3450) SIG_NAME M_H_DQ<35>
J 0
(-1890 3460);
DISPLAY 0.659574 (-1890 3460);
PAINT MONO (-1890 3460);
DISPLAY INVISIBLE (-1890 3460);
FORCEPROP 1 LASTPIN (-1900 3450) BN 35
J 2
(-1850 3460);
DISPLAY 0.617021 (-1850 3460);
PAINT PINK (-1850 3460);
FORCEPROP 2 LAST CDS_LIB mstr_standard
J 2
(-1850 3450);
DISPLAY 0.787234 (-1850 3450);
PAINT MONO (-1850 3450);
DISPLAY INVISIBLE (-1850 3450);
FORCEPROP 1 LAST BODY_TYPE PLUMBING
J 2
(-1850 3400);
DISPLAY 1.234043 (-1850 3400);
PAINT GREEN (-1850 3400);
DISPLAY INVISIBLE (-1850 3400);
FORCEPROP 1 LAST HDL_TAP TRUE
J 2
(-2175 3325);
DISPLAY 1.234043 (-2175 3325);
PAINT GREEN (-2175 3325);
DISPLAY INVISIBLE (-2175 3325);
FORCEPROP 1 LAST PATH I79
J 2
(-1850 3450);
DISPLAY 0.936170 (-1850 3450);
PAINT GREEN (-1850 3450);
DISPLAY INVISIBLE (-1850 3450);
FORCEADD TAP..6
R 2
(650 5050);
FORCEPROP 3 LASTPIN (600 5050) SIG_NAME M_H_DQS_DP<16>
J 0
(610 5060);
DISPLAY 0.659574 (610 5060);
PAINT MONO (610 5060);
DISPLAY INVISIBLE (610 5060);
FORCEPROP 1 LASTPIN (600 5050) BN 16
J 2
(650 5060);
DISPLAY 0.617021 (650 5060);
PAINT PINK (650 5060);
FORCEPROP 2 LAST CDS_LIB mstr_standard
J 0
(650 5050);
DISPLAY 0.787234 (650 5050);
PAINT MONO (650 5050);
DISPLAY INVISIBLE (650 5050);
FORCEPROP 1 LAST BODY_TYPE PLUMBING
J 2
(650 5000);
DISPLAY 1.234043 (650 5000);
PAINT GREEN (650 5000);
DISPLAY INVISIBLE (650 5000);
FORCEPROP 1 LAST HDL_TAP TRUE
J 2
(325 4925);
DISPLAY 1.234043 (325 4925);
PAINT GREEN (325 4925);
DISPLAY INVISIBLE (325 4925);
FORCEPROP 1 LAST PATH I8
J 2
(650 5050);
DISPLAY 0.936170 (650 5050);
PAINT GREEN (650 5050);
DISPLAY INVISIBLE (650 5050);
FORCEADD TAP..6
R 2
(-1850 3100);
FORCEPROP 3 LASTPIN (-1900 3100) SIG_NAME M_H_DQ<26>
J 0
(-1890 3110);
DISPLAY 0.659574 (-1890 3110);
PAINT MONO (-1890 3110);
DISPLAY INVISIBLE (-1890 3110);
FORCEPROP 1 LASTPIN (-1900 3100) BN 26
J 2
(-1850 3110);
DISPLAY 0.617021 (-1850 3110);
PAINT PINK (-1850 3110);
FORCEPROP 2 LAST CDS_LIB mstr_standard
J 2
(-1850 3100);
DISPLAY 0.787234 (-1850 3100);
PAINT MONO (-1850 3100);
DISPLAY INVISIBLE (-1850 3100);
FORCEPROP 1 LAST BODY_TYPE PLUMBING
J 2
(-1850 3050);
DISPLAY 1.234043 (-1850 3050);
PAINT GREEN (-1850 3050);
DISPLAY INVISIBLE (-1850 3050);
FORCEPROP 1 LAST HDL_TAP TRUE
J 2
(-2175 2975);
DISPLAY 1.234043 (-2175 2975);
PAINT GREEN (-2175 2975);
DISPLAY INVISIBLE (-2175 2975);
FORCEPROP 1 LAST PATH I80
J 2
(-1850 3100);
DISPLAY 0.936170 (-1850 3100);
PAINT GREEN (-1850 3100);
DISPLAY INVISIBLE (-1850 3100);
FORCEADD TAP..6
R 2
(-1850 3150);
FORCEPROP 3 LASTPIN (-1900 3150) SIG_NAME M_H_DQ<29>
J 0
(-1890 3160);
DISPLAY 0.659574 (-1890 3160);
PAINT MONO (-1890 3160);
DISPLAY INVISIBLE (-1890 3160);
FORCEPROP 1 LASTPIN (-1900 3150) BN 29
J 2
(-1850 3160);
DISPLAY 0.617021 (-1850 3160);
PAINT PINK (-1850 3160);
FORCEPROP 2 LAST CDS_LIB mstr_standard
J 2
(-1850 3150);
DISPLAY 0.787234 (-1850 3150);
PAINT MONO (-1850 3150);
DISPLAY INVISIBLE (-1850 3150);
FORCEPROP 1 LAST BODY_TYPE PLUMBING
J 2
(-1850 3100);
DISPLAY 1.234043 (-1850 3100);
PAINT GREEN (-1850 3100);
DISPLAY INVISIBLE (-1850 3100);
FORCEPROP 1 LAST HDL_TAP TRUE
J 2
(-2175 3025);
DISPLAY 1.234043 (-2175 3025);
PAINT GREEN (-2175 3025);
DISPLAY INVISIBLE (-2175 3025);
FORCEPROP 1 LAST PATH I81
J 2
(-1850 3150);
DISPLAY 0.936170 (-1850 3150);
PAINT GREEN (-1850 3150);
DISPLAY INVISIBLE (-1850 3150);
FORCEADD TAP..6
R 2
(-1850 3050);
FORCEPROP 3 LASTPIN (-1900 3050) SIG_NAME M_H_DQ<27>
J 0
(-1890 3060);
DISPLAY 0.659574 (-1890 3060);
PAINT MONO (-1890 3060);
DISPLAY INVISIBLE (-1890 3060);
FORCEPROP 1 LASTPIN (-1900 3050) BN 27
J 2
(-1850 3060);
DISPLAY 0.617021 (-1850 3060);
PAINT PINK (-1850 3060);
FORCEPROP 2 LAST CDS_LIB mstr_standard
J 2
(-1850 3050);
DISPLAY 0.787234 (-1850 3050);
PAINT MONO (-1850 3050);
DISPLAY INVISIBLE (-1850 3050);
FORCEPROP 1 LAST BODY_TYPE PLUMBING
J 2
(-1850 3000);
DISPLAY 1.234043 (-1850 3000);
PAINT GREEN (-1850 3000);
DISPLAY INVISIBLE (-1850 3000);
FORCEPROP 1 LAST HDL_TAP TRUE
J 2
(-2175 2925);
DISPLAY 1.234043 (-2175 2925);
PAINT GREEN (-2175 2925);
DISPLAY INVISIBLE (-2175 2925);
FORCEPROP 1 LAST PATH I82
J 2
(-1850 3050);
DISPLAY 0.936170 (-1850 3050);
PAINT GREEN (-1850 3050);
DISPLAY INVISIBLE (-1850 3050);
FORCEADD TAP..6
R 2
(-1850 3200);
FORCEPROP 3 LASTPIN (-1900 3200) SIG_NAME M_H_DQ<28>
J 0
(-1890 3210);
DISPLAY 0.659574 (-1890 3210);
PAINT MONO (-1890 3210);
DISPLAY INVISIBLE (-1890 3210);
FORCEPROP 1 LASTPIN (-1900 3200) BN 28
J 2
(-1850 3210);
DISPLAY 0.617021 (-1850 3210);
PAINT PINK (-1850 3210);
FORCEPROP 2 LAST CDS_LIB mstr_standard
J 2
(-1850 3200);
DISPLAY 0.787234 (-1850 3200);
PAINT MONO (-1850 3200);
DISPLAY INVISIBLE (-1850 3200);
FORCEPROP 1 LAST BODY_TYPE PLUMBING
J 2
(-1850 3150);
DISPLAY 1.234043 (-1850 3150);
PAINT GREEN (-1850 3150);
DISPLAY INVISIBLE (-1850 3150);
FORCEPROP 1 LAST HDL_TAP TRUE
J 2
(-2175 3075);
DISPLAY 1.234043 (-2175 3075);
PAINT GREEN (-2175 3075);
DISPLAY INVISIBLE (-2175 3075);
FORCEPROP 1 LAST PATH I83
J 2
(-1850 3200);
DISPLAY 0.936170 (-1850 3200);
PAINT GREEN (-1850 3200);
DISPLAY INVISIBLE (-1850 3200);
FORCEADD TAP..6
R 2
(-1850 3250);
FORCEPROP 3 LASTPIN (-1900 3250) SIG_NAME M_H_DQ<31>
J 0
(-1890 3260);
DISPLAY 0.659574 (-1890 3260);
PAINT MONO (-1890 3260);
DISPLAY INVISIBLE (-1890 3260);
FORCEPROP 1 LASTPIN (-1900 3250) BN 31
J 2
(-1850 3260);
DISPLAY 0.617021 (-1850 3260);
PAINT PINK (-1850 3260);
FORCEPROP 2 LAST CDS_LIB mstr_standard
J 2
(-1850 3250);
DISPLAY 0.787234 (-1850 3250);
PAINT MONO (-1850 3250);
DISPLAY INVISIBLE (-1850 3250);
FORCEPROP 1 LAST BODY_TYPE PLUMBING
J 2
(-1850 3200);
DISPLAY 1.234043 (-1850 3200);
PAINT GREEN (-1850 3200);
DISPLAY INVISIBLE (-1850 3200);
FORCEPROP 1 LAST HDL_TAP TRUE
J 2
(-2175 3125);
DISPLAY 1.234043 (-2175 3125);
PAINT GREEN (-2175 3125);
DISPLAY INVISIBLE (-2175 3125);
FORCEPROP 1 LAST PATH I84
J 2
(-1850 3250);
DISPLAY 0.936170 (-1850 3250);
PAINT GREEN (-1850 3250);
DISPLAY INVISIBLE (-1850 3250);
FORCEADD TAP..6
R 2
(-1850 2850);
FORCEPROP 3 LASTPIN (-1900 2850) SIG_NAME M_H_DQ<23>
J 0
(-1890 2860);
DISPLAY 0.659574 (-1890 2860);
PAINT MONO (-1890 2860);
DISPLAY INVISIBLE (-1890 2860);
FORCEPROP 1 LASTPIN (-1900 2850) BN 23
J 2
(-1850 2860);
DISPLAY 0.617021 (-1850 2860);
PAINT PINK (-1850 2860);
FORCEPROP 2 LAST CDS_LIB mstr_standard
J 2
(-1850 2850);
DISPLAY 0.787234 (-1850 2850);
PAINT MONO (-1850 2850);
DISPLAY INVISIBLE (-1850 2850);
FORCEPROP 1 LAST BODY_TYPE PLUMBING
J 2
(-1850 2800);
DISPLAY 1.234043 (-1850 2800);
PAINT GREEN (-1850 2800);
DISPLAY INVISIBLE (-1850 2800);
FORCEPROP 1 LAST HDL_TAP TRUE
J 2
(-2175 2725);
DISPLAY 1.234043 (-2175 2725);
PAINT GREEN (-2175 2725);
DISPLAY INVISIBLE (-2175 2725);
FORCEPROP 1 LAST PATH I85
J 2
(-1850 2850);
DISPLAY 0.936170 (-1850 2850);
PAINT GREEN (-1850 2850);
DISPLAY INVISIBLE (-1850 2850);
FORCEADD TAP..6
R 2
(-1850 2900);
FORCEPROP 3 LASTPIN (-1900 2900) SIG_NAME M_H_DQ<22>
J 0
(-1890 2910);
DISPLAY 0.659574 (-1890 2910);
PAINT MONO (-1890 2910);
DISPLAY INVISIBLE (-1890 2910);
FORCEPROP 1 LASTPIN (-1900 2900) BN 22
J 2
(-1850 2910);
DISPLAY 0.617021 (-1850 2910);
PAINT PINK (-1850 2910);
FORCEPROP 2 LAST CDS_LIB mstr_standard
J 2
(-1850 2900);
DISPLAY 0.787234 (-1850 2900);
PAINT MONO (-1850 2900);
DISPLAY INVISIBLE (-1850 2900);
FORCEPROP 1 LAST BODY_TYPE PLUMBING
J 2
(-1850 2850);
DISPLAY 1.234043 (-1850 2850);
PAINT GREEN (-1850 2850);
DISPLAY INVISIBLE (-1850 2850);
FORCEPROP 1 LAST HDL_TAP TRUE
J 2
(-2175 2775);
DISPLAY 1.234043 (-2175 2775);
PAINT GREEN (-2175 2775);
DISPLAY INVISIBLE (-2175 2775);
FORCEPROP 1 LAST PATH I86
J 2
(-1850 2900);
DISPLAY 0.936170 (-1850 2900);
PAINT GREEN (-1850 2900);
DISPLAY INVISIBLE (-1850 2900);
FORCEADD TAP..6
R 2
(-1850 2800);
FORCEPROP 3 LASTPIN (-1900 2800) SIG_NAME M_H_DQ<20>
J 0
(-1890 2810);
DISPLAY 0.659574 (-1890 2810);
PAINT MONO (-1890 2810);
DISPLAY INVISIBLE (-1890 2810);
FORCEPROP 1 LASTPIN (-1900 2800) BN 20
J 2
(-1850 2810);
DISPLAY 0.617021 (-1850 2810);
PAINT PINK (-1850 2810);
FORCEPROP 2 LAST CDS_LIB mstr_standard
J 2
(-1850 2800);
DISPLAY 0.787234 (-1850 2800);
PAINT MONO (-1850 2800);
DISPLAY INVISIBLE (-1850 2800);
FORCEPROP 1 LAST BODY_TYPE PLUMBING
J 2
(-1850 2750);
DISPLAY 1.234043 (-1850 2750);
PAINT GREEN (-1850 2750);
DISPLAY INVISIBLE (-1850 2750);
FORCEPROP 1 LAST HDL_TAP TRUE
J 2
(-2175 2675);
DISPLAY 1.234043 (-2175 2675);
PAINT GREEN (-2175 2675);
DISPLAY INVISIBLE (-2175 2675);
FORCEPROP 1 LAST PATH I87
J 2
(-1850 2800);
DISPLAY 0.936170 (-1850 2800);
PAINT GREEN (-1850 2800);
DISPLAY INVISIBLE (-1850 2800);
FORCEADD TAP..6
R 2
(-1850 3000);
FORCEPROP 3 LASTPIN (-1900 3000) SIG_NAME M_H_DQ<24>
J 0
(-1890 3010);
DISPLAY 0.659574 (-1890 3010);
PAINT MONO (-1890 3010);
DISPLAY INVISIBLE (-1890 3010);
FORCEPROP 1 LASTPIN (-1900 3000) BN 24
J 2
(-1850 3010);
DISPLAY 0.617021 (-1850 3010);
PAINT PINK (-1850 3010);
FORCEPROP 2 LAST CDS_LIB mstr_standard
J 2
(-1850 3000);
DISPLAY 0.787234 (-1850 3000);
PAINT MONO (-1850 3000);
DISPLAY INVISIBLE (-1850 3000);
FORCEPROP 1 LAST BODY_TYPE PLUMBING
J 2
(-1850 2950);
DISPLAY 1.234043 (-1850 2950);
PAINT GREEN (-1850 2950);
DISPLAY INVISIBLE (-1850 2950);
FORCEPROP 1 LAST HDL_TAP TRUE
J 2
(-2175 2875);
DISPLAY 1.234043 (-2175 2875);
PAINT GREEN (-2175 2875);
DISPLAY INVISIBLE (-2175 2875);
FORCEPROP 1 LAST PATH I88
J 2
(-1850 3000);
DISPLAY 0.936170 (-1850 3000);
PAINT GREEN (-1850 3000);
DISPLAY INVISIBLE (-1850 3000);
FORCEADD TAP..6
R 2
(-1850 2950);
FORCEPROP 3 LASTPIN (-1900 2950) SIG_NAME M_H_DQ<25>
J 0
(-1890 2960);
DISPLAY 0.659574 (-1890 2960);
PAINT MONO (-1890 2960);
DISPLAY INVISIBLE (-1890 2960);
FORCEPROP 1 LASTPIN (-1900 2950) BN 25
J 2
(-1850 2960);
DISPLAY 0.617021 (-1850 2960);
PAINT PINK (-1850 2960);
FORCEPROP 2 LAST CDS_LIB mstr_standard
J 2
(-1850 2950);
DISPLAY 0.787234 (-1850 2950);
PAINT MONO (-1850 2950);
DISPLAY INVISIBLE (-1850 2950);
FORCEPROP 1 LAST BODY_TYPE PLUMBING
J 2
(-1850 2900);
DISPLAY 1.234043 (-1850 2900);
PAINT GREEN (-1850 2900);
DISPLAY INVISIBLE (-1850 2900);
FORCEPROP 1 LAST HDL_TAP TRUE
J 2
(-2175 2825);
DISPLAY 1.234043 (-2175 2825);
PAINT GREEN (-2175 2825);
DISPLAY INVISIBLE (-2175 2825);
FORCEPROP 1 LAST PATH I89
J 2
(-1850 2950);
DISPLAY 0.936170 (-1850 2950);
PAINT GREEN (-1850 2950);
DISPLAY INVISIBLE (-1850 2950);
FORCEADD TAP..6
R 2
(650 5150);
FORCEPROP 3 LASTPIN (600 5150) SIG_NAME M_H_DQS_DP<17>
J 0
(610 5160);
DISPLAY 0.659574 (610 5160);
PAINT MONO (610 5160);
DISPLAY INVISIBLE (610 5160);
FORCEPROP 1 LASTPIN (600 5150) BN 17
J 2
(650 5160);
DISPLAY 0.617021 (650 5160);
PAINT PINK (650 5160);
FORCEPROP 2 LAST CDS_LIB mstr_standard
J 2
(650 5150);
DISPLAY 0.787234 (650 5150);
PAINT MONO (650 5150);
DISPLAY INVISIBLE (650 5150);
FORCEPROP 1 LAST BODY_TYPE PLUMBING
J 2
(650 5100);
DISPLAY 1.234043 (650 5100);
PAINT GREEN (650 5100);
DISPLAY INVISIBLE (650 5100);
FORCEPROP 1 LAST HDL_TAP TRUE
J 2
(325 5025);
DISPLAY 1.234043 (325 5025);
PAINT GREEN (325 5025);
DISPLAY INVISIBLE (325 5025);
FORCEPROP 1 LAST PATH I9
J 2
(650 5150);
DISPLAY 0.936170 (650 5150);
PAINT GREEN (650 5150);
DISPLAY INVISIBLE (650 5150);
FORCEADD TAP..6
R 2
(-1850 2550);
FORCEPROP 3 LASTPIN (-1900 2550) SIG_NAME M_H_DQ<17>
J 0
(-1890 2560);
DISPLAY 0.659574 (-1890 2560);
PAINT MONO (-1890 2560);
DISPLAY INVISIBLE (-1890 2560);
FORCEPROP 1 LASTPIN (-1900 2550) BN 17
J 2
(-1850 2560);
DISPLAY 0.617021 (-1850 2560);
PAINT PINK (-1850 2560);
FORCEPROP 2 LAST CDS_LIB mstr_standard
J 2
(-1850 2550);
DISPLAY 0.787234 (-1850 2550);
PAINT MONO (-1850 2550);
DISPLAY INVISIBLE (-1850 2550);
FORCEPROP 1 LAST BODY_TYPE PLUMBING
J 2
(-1850 2500);
DISPLAY 1.234043 (-1850 2500);
PAINT GREEN (-1850 2500);
DISPLAY INVISIBLE (-1850 2500);
FORCEPROP 1 LAST HDL_TAP TRUE
J 2
(-2175 2425);
DISPLAY 1.234043 (-2175 2425);
PAINT GREEN (-2175 2425);
DISPLAY INVISIBLE (-2175 2425);
FORCEPROP 1 LAST PATH I90
J 2
(-1850 2550);
DISPLAY 0.936170 (-1850 2550);
PAINT GREEN (-1850 2550);
DISPLAY INVISIBLE (-1850 2550);
FORCEADD TAP..6
R 2
(-1850 2600);
FORCEPROP 3 LASTPIN (-1900 2600) SIG_NAME M_H_DQ<16>
J 0
(-1890 2610);
DISPLAY 0.659574 (-1890 2610);
PAINT MONO (-1890 2610);
DISPLAY INVISIBLE (-1890 2610);
FORCEPROP 1 LASTPIN (-1900 2600) BN 16
J 2
(-1850 2610);
DISPLAY 0.617021 (-1850 2610);
PAINT PINK (-1850 2610);
FORCEPROP 2 LAST CDS_LIB mstr_standard
J 2
(-1850 2600);
DISPLAY 0.787234 (-1850 2600);
PAINT MONO (-1850 2600);
DISPLAY INVISIBLE (-1850 2600);
FORCEPROP 1 LAST BODY_TYPE PLUMBING
J 2
(-1850 2550);
DISPLAY 1.234043 (-1850 2550);
PAINT GREEN (-1850 2550);
DISPLAY INVISIBLE (-1850 2550);
FORCEPROP 1 LAST HDL_TAP TRUE
J 2
(-2175 2475);
DISPLAY 1.234043 (-2175 2475);
PAINT GREEN (-2175 2475);
DISPLAY INVISIBLE (-2175 2475);
FORCEPROP 1 LAST PATH I91
J 2
(-1850 2600);
DISPLAY 0.936170 (-1850 2600);
PAINT GREEN (-1850 2600);
DISPLAY INVISIBLE (-1850 2600);
FORCEADD TAP..6
R 2
(-1850 2650);
FORCEPROP 3 LASTPIN (-1900 2650) SIG_NAME M_H_DQ<19>
J 0
(-1890 2660);
DISPLAY 0.659574 (-1890 2660);
PAINT MONO (-1890 2660);
DISPLAY INVISIBLE (-1890 2660);
FORCEPROP 1 LASTPIN (-1900 2650) BN 19
J 2
(-1850 2660);
DISPLAY 0.617021 (-1850 2660);
PAINT PINK (-1850 2660);
FORCEPROP 2 LAST CDS_LIB mstr_standard
J 2
(-1850 2650);
DISPLAY 0.787234 (-1850 2650);
PAINT MONO (-1850 2650);
DISPLAY INVISIBLE (-1850 2650);
FORCEPROP 1 LAST BODY_TYPE PLUMBING
J 2
(-1850 2600);
DISPLAY 1.234043 (-1850 2600);
PAINT GREEN (-1850 2600);
DISPLAY INVISIBLE (-1850 2600);
FORCEPROP 1 LAST HDL_TAP TRUE
J 2
(-2175 2525);
DISPLAY 1.234043 (-2175 2525);
PAINT GREEN (-2175 2525);
DISPLAY INVISIBLE (-2175 2525);
FORCEPROP 1 LAST PATH I92
J 2
(-1850 2650);
DISPLAY 0.936170 (-1850 2650);
PAINT GREEN (-1850 2650);
DISPLAY INVISIBLE (-1850 2650);
FORCEADD TAP..6
R 2
(-1850 2700);
FORCEPROP 3 LASTPIN (-1900 2700) SIG_NAME M_H_DQ<18>
J 0
(-1890 2710);
DISPLAY 0.659574 (-1890 2710);
PAINT MONO (-1890 2710);
DISPLAY INVISIBLE (-1890 2710);
FORCEPROP 1 LASTPIN (-1900 2700) BN 18
J 2
(-1850 2710);
DISPLAY 0.617021 (-1850 2710);
PAINT PINK (-1850 2710);
FORCEPROP 2 LAST CDS_LIB mstr_standard
J 2
(-1850 2700);
DISPLAY 0.787234 (-1850 2700);
PAINT MONO (-1850 2700);
DISPLAY INVISIBLE (-1850 2700);
FORCEPROP 1 LAST BODY_TYPE PLUMBING
J 2
(-1850 2650);
DISPLAY 1.234043 (-1850 2650);
PAINT GREEN (-1850 2650);
DISPLAY INVISIBLE (-1850 2650);
FORCEPROP 1 LAST HDL_TAP TRUE
J 2
(-2175 2575);
DISPLAY 1.234043 (-2175 2575);
PAINT GREEN (-2175 2575);
DISPLAY INVISIBLE (-2175 2575);
FORCEPROP 1 LAST PATH I93
J 2
(-1850 2700);
DISPLAY 0.936170 (-1850 2700);
PAINT GREEN (-1850 2700);
DISPLAY INVISIBLE (-1850 2700);
FORCEADD TAP..6
R 2
(-1850 2750);
FORCEPROP 3 LASTPIN (-1900 2750) SIG_NAME M_H_DQ<21>
J 0
(-1890 2760);
DISPLAY 0.659574 (-1890 2760);
PAINT MONO (-1890 2760);
DISPLAY INVISIBLE (-1890 2760);
FORCEPROP 1 LASTPIN (-1900 2750) BN 21
J 2
(-1850 2760);
DISPLAY 0.617021 (-1850 2760);
PAINT PINK (-1850 2760);
FORCEPROP 2 LAST CDS_LIB mstr_standard
J 2
(-1850 2750);
DISPLAY 0.787234 (-1850 2750);
PAINT MONO (-1850 2750);
DISPLAY INVISIBLE (-1850 2750);
FORCEPROP 1 LAST BODY_TYPE PLUMBING
J 2
(-1850 2700);
DISPLAY 1.234043 (-1850 2700);
PAINT GREEN (-1850 2700);
DISPLAY INVISIBLE (-1850 2700);
FORCEPROP 1 LAST HDL_TAP TRUE
J 2
(-2175 2625);
DISPLAY 1.234043 (-2175 2625);
PAINT GREEN (-2175 2625);
DISPLAY INVISIBLE (-2175 2625);
FORCEPROP 1 LAST PATH I94
J 2
(-1850 2750);
DISPLAY 0.936170 (-1850 2750);
PAINT GREEN (-1850 2750);
DISPLAY INVISIBLE (-1850 2750);
FORCEADD TAP..6
R 2
(-1850 2300);
FORCEPROP 3 LASTPIN (-1900 2300) SIG_NAME M_H_DQ<10>
J 0
(-1890 2310);
DISPLAY 0.659574 (-1890 2310);
PAINT MONO (-1890 2310);
DISPLAY INVISIBLE (-1890 2310);
FORCEPROP 1 LASTPIN (-1900 2300) BN 10
J 2
(-1850 2310);
DISPLAY 0.617021 (-1850 2310);
PAINT PINK (-1850 2310);
FORCEPROP 2 LAST CDS_LIB mstr_standard
J 2
(-1850 2300);
DISPLAY 0.787234 (-1850 2300);
PAINT MONO (-1850 2300);
DISPLAY INVISIBLE (-1850 2300);
FORCEPROP 1 LAST BODY_TYPE PLUMBING
J 2
(-1850 2250);
DISPLAY 1.234043 (-1850 2250);
PAINT GREEN (-1850 2250);
DISPLAY INVISIBLE (-1850 2250);
FORCEPROP 1 LAST HDL_TAP TRUE
J 2
(-2175 2175);
DISPLAY 1.234043 (-2175 2175);
PAINT GREEN (-2175 2175);
DISPLAY INVISIBLE (-2175 2175);
FORCEPROP 1 LAST PATH I95
J 2
(-1850 2300);
DISPLAY 0.936170 (-1850 2300);
PAINT GREEN (-1850 2300);
DISPLAY INVISIBLE (-1850 2300);
FORCEADD TAP..6
R 2
(-1850 2400);
FORCEPROP 3 LASTPIN (-1900 2400) SIG_NAME M_H_DQ<12>
J 0
(-1890 2410);
DISPLAY 0.659574 (-1890 2410);
PAINT MONO (-1890 2410);
DISPLAY INVISIBLE (-1890 2410);
FORCEPROP 1 LASTPIN (-1900 2400) BN 12
J 2
(-1850 2410);
DISPLAY 0.617021 (-1850 2410);
PAINT PINK (-1850 2410);
FORCEPROP 2 LAST CDS_LIB mstr_standard
J 2
(-1850 2400);
DISPLAY 0.787234 (-1850 2400);
PAINT MONO (-1850 2400);
DISPLAY INVISIBLE (-1850 2400);
FORCEPROP 1 LAST BODY_TYPE PLUMBING
J 2
(-1850 2350);
DISPLAY 1.234043 (-1850 2350);
PAINT GREEN (-1850 2350);
DISPLAY INVISIBLE (-1850 2350);
FORCEPROP 1 LAST HDL_TAP TRUE
J 2
(-2175 2275);
DISPLAY 1.234043 (-2175 2275);
PAINT GREEN (-2175 2275);
DISPLAY INVISIBLE (-2175 2275);
FORCEPROP 1 LAST PATH I96
J 2
(-1850 2400);
DISPLAY 0.936170 (-1850 2400);
PAINT GREEN (-1850 2400);
DISPLAY INVISIBLE (-1850 2400);
FORCEADD TAP..6
R 2
(-1850 2350);
FORCEPROP 3 LASTPIN (-1900 2350) SIG_NAME M_H_DQ<13>
J 0
(-1890 2360);
DISPLAY 0.659574 (-1890 2360);
PAINT MONO (-1890 2360);
DISPLAY INVISIBLE (-1890 2360);
FORCEPROP 1 LASTPIN (-1900 2350) BN 13
J 2
(-1850 2360);
DISPLAY 0.617021 (-1850 2360);
PAINT PINK (-1850 2360);
FORCEPROP 2 LAST CDS_LIB mstr_standard
J 2
(-1850 2350);
DISPLAY 0.787234 (-1850 2350);
PAINT MONO (-1850 2350);
DISPLAY INVISIBLE (-1850 2350);
FORCEPROP 1 LAST BODY_TYPE PLUMBING
J 2
(-1850 2300);
DISPLAY 1.234043 (-1850 2300);
PAINT GREEN (-1850 2300);
DISPLAY INVISIBLE (-1850 2300);
FORCEPROP 1 LAST HDL_TAP TRUE
J 2
(-2175 2225);
DISPLAY 1.234043 (-2175 2225);
PAINT GREEN (-2175 2225);
DISPLAY INVISIBLE (-2175 2225);
FORCEPROP 1 LAST PATH I97
J 2
(-1850 2350);
DISPLAY 0.936170 (-1850 2350);
PAINT GREEN (-1850 2350);
DISPLAY INVISIBLE (-1850 2350);
FORCEADD TAP..6
R 2
(-1850 2450);
FORCEPROP 3 LASTPIN (-1900 2450) SIG_NAME M_H_DQ<15>
J 0
(-1890 2460);
DISPLAY 0.659574 (-1890 2460);
PAINT MONO (-1890 2460);
DISPLAY INVISIBLE (-1890 2460);
FORCEPROP 1 LASTPIN (-1900 2450) BN 15
J 2
(-1850 2460);
DISPLAY 0.617021 (-1850 2460);
PAINT PINK (-1850 2460);
FORCEPROP 2 LAST CDS_LIB mstr_standard
J 2
(-1850 2450);
DISPLAY 0.787234 (-1850 2450);
PAINT MONO (-1850 2450);
DISPLAY INVISIBLE (-1850 2450);
FORCEPROP 1 LAST BODY_TYPE PLUMBING
J 2
(-1850 2400);
DISPLAY 1.234043 (-1850 2400);
PAINT GREEN (-1850 2400);
DISPLAY INVISIBLE (-1850 2400);
FORCEPROP 1 LAST HDL_TAP TRUE
J 2
(-2175 2325);
DISPLAY 1.234043 (-2175 2325);
PAINT GREEN (-2175 2325);
DISPLAY INVISIBLE (-2175 2325);
FORCEPROP 1 LAST PATH I98
J 2
(-1850 2450);
DISPLAY 0.936170 (-1850 2450);
PAINT GREEN (-1850 2450);
DISPLAY INVISIBLE (-1850 2450);
FORCEADD TAP..6
R 2
(-1850 2500);
FORCEPROP 3 LASTPIN (-1900 2500) SIG_NAME M_H_DQ<14>
J 0
(-1890 2510);
DISPLAY 0.659574 (-1890 2510);
PAINT MONO (-1890 2510);
DISPLAY INVISIBLE (-1890 2510);
FORCEPROP 1 LASTPIN (-1900 2500) BN 14
J 2
(-1850 2510);
DISPLAY 0.617021 (-1850 2510);
PAINT PINK (-1850 2510);
FORCEPROP 2 LAST CDS_LIB mstr_standard
J 2
(-1850 2500);
DISPLAY 0.787234 (-1850 2500);
PAINT MONO (-1850 2500);
DISPLAY INVISIBLE (-1850 2500);
FORCEPROP 1 LAST BODY_TYPE PLUMBING
J 2
(-1850 2450);
DISPLAY 1.234043 (-1850 2450);
PAINT GREEN (-1850 2450);
DISPLAY INVISIBLE (-1850 2450);
FORCEPROP 1 LAST HDL_TAP TRUE
J 2
(-2175 2375);
DISPLAY 1.234043 (-2175 2375);
PAINT GREEN (-2175 2375);
DISPLAY INVISIBLE (-2175 2375);
FORCEPROP 1 LAST PATH I99
J 2
(-1850 2500);
DISPLAY 0.936170 (-1850 2500);
PAINT GREEN (-1850 2500);
DISPLAY INVISIBLE (-1850 2500);
FORCEADD INTEL_CORP_BPAGE..1
(2650 500);
FORCEPROP 1 LAST CDS_CON_LAST_MODIFIED Fri Jun 16 17:48:29 2017
J 0
(1225 825);
DISPLAY 0.787234 (1225 825);
PAINT ORANGE (1225 825);
DISPLAY INVISIBLE (1225 825);
FORCEPROP 1 LAST CUSTOM_TXT_CDS <CURRENT_DESIGN_SHEET> OF <TOTAL_DESIGN_SHEETS>
J 0
(2150 525);
PAINT ORANGE (2150 525);
FORCEPROP 2 LAST CUSTOM_TXT_CDS <XR_PAGE_TITLE>
J 0
(-5240 5750);
DISPLAY 0.638298 (-5240 5750);
PAINT PINK (-5240 5750);
DISPLAY INVISIBLE (-5240 5750);
FORCEPROP 2 LAST CUSTOM_TXT_CDS <CON_LAST_MODIFIED>
J 0
(-1350 575);
DISPLAY 1.042553 (-1350 575);
PAINT ORANGE (-1350 575);
FORCEPROP 1 LAST SCH_TITLE CPU1 DDR4 CH H DIMM0
J 0
(-5300 550);
DISPLAY 1.212766 (-5300 550);
PAINT WHITE (-5300 550);
FORCEPROP 2 LAST CDS_LIB mstr_symbols
J 0
(2650 500);
DISPLAY 0.787234 (2650 500);
PAINT MONO (2650 500);
DISPLAY INVISIBLE (2650 500);
FORCEPROP 2 LAST PAGE_BORDER TRUE
J 0
(-5240 5750);
DISPLAY 0.680851 (-5240 5750);
PAINT PINK (-5240 5750);
DISPLAY INVISIBLE (-5240 5750);
FORCEPROP 1 LAST COMMENT_BODY TRUE
J 0
(2660 510);
DISPLAY 0.382979 (2660 510);
PAINT GREEN (2660 510);
DISPLAY INVISIBLE (2660 510);
FORCEPROP 2 LAST CDS_XR_PAGE_TITLE CR-79 : @BASEBOARD_FAB2_LIB.BASEBOARD_FAB2(SCH_1):PAGE79
J 0
(-5240 5750);
DISPLAY 0.638298 (-5240 5750);
PAINT PINK (-5240 5750);
DISPLAY INVISIBLE (-5240 5750);
FORCEADD BOM_NOTE..1
(-5050 5275);
FORCEPROP 0 LAST L1 STUFF FOR SKU A & B
J 0
(-5200 5175);
DISPLAY 1.063830 (-5200 5175);
PAINT WHITE (-5200 5175);
FORCEPROP 2 LAST CDS_LIB mstr_symbols
J 0
(-5050 5275);
PAINT ORANGE (-5050 5275);
DISPLAY INVISIBLE (-5050 5275);
FORCEPROP 2 LAST BOM_COST SB
J 0
(-5200 5250);
DISPLAY 1.361702 (-5200 5250);
PAINT ORANGE (-5200 5250);
DISPLAY INVISIBLE (-5200 5250);
FORCEPROP 1 LAST COMMENT_BODY TRUE
J 0
(-5025 5375);
DISPLAY 1.319149 (-5025 5375);
PAINT ORANGE (-5025 5375);
DISPLAY INVISIBLE (-5025 5375);
FORCEPROP 2 LAST ROOM SB_HEADERS
J 0
(-5200 5250);
DISPLAY 1.361702 (-5200 5250);
PAINT ORANGE (-5200 5250);
DISPLAY INVISIBLE (-5200 5250);
WIRE 16 -1 (-1525 2475)(-1525 2400);
WIRE 16 -1 (-1525 2400)(-1150 2400);
WIRE 16 -1 (-1150 2350)(-1150 2400);
WIRE 16 -1 (-1150 2400)(-950 2400);
WIRE 16 -1 (-1150 2300)(-1150 2350);
WIRE 16 -1 (-1150 2350)(-950 2350);
WIRE 16 -1 (-1150 2250)(-1150 2300);
WIRE 16 -1 (-1150 2300)(-950 2300);
WIRE 16 -1 (-1150 2200)(-1150 2250);
WIRE 16 -1 (-1150 2250)(-950 2250);
WIRE 16 -1 (-1150 2150)(-1150 2200);
WIRE 16 -1 (-1150 2200)(-950 2200);
WIRE 16 -1 (-1150 2100)(-1150 2150);
WIRE 16 -1 (-1150 2150)(-950 2150);
WIRE 16 -1 (-1150 2050)(-1150 2100);
WIRE 16 -1 (-1150 2100)(-950 2100);
WIRE 16 -1 (-1150 2000)(-1150 2050);
WIRE 16 -1 (-1150 2050)(-950 2050);
WIRE 16 -1 (-1150 1950)(-1150 2000);
WIRE 16 -1 (-1150 2000)(-950 2000);
WIRE 16 -1 (-1150 1900)(-1150 1950);
WIRE 16 -1 (-1150 1950)(-950 1950);
WIRE 16 -1 (-1150 1850)(-1150 1900);
WIRE 16 -1 (-1150 1900)(-950 1900);
WIRE 16 -1 (-1150 1800)(-1150 1850);
WIRE 16 -1 (-1150 1850)(-950 1850);
WIRE 16 -1 (-1150 1750)(-1150 1800);
WIRE 16 -1 (-1150 1800)(-950 1800);
WIRE 16 -1 (-1150 1700)(-1150 1750);
WIRE 16 -1 (-1150 1750)(-950 1750);
WIRE 16 -1 (-1150 1650)(-1150 1700);
WIRE 16 -1 (-1150 1700)(-950 1700);
WIRE 16 -1 (-1150 1600)(-1150 1650);
WIRE 16 -1 (-1150 1650)(-950 1650);
WIRE 16 -1 (-1150 1550)(-1150 1600);
WIRE 16 -1 (-1150 1600)(-950 1600);
WIRE 16 -1 (-1150 1500)(-1150 1550);
WIRE 16 -1 (-1150 1550)(-950 1550);
WIRE 16 -1 (-1150 1450)(-1150 1500);
WIRE 16 -1 (-1150 1500)(-950 1500);
WIRE 16 -1 (-1150 1400)(-1150 1450);
WIRE 16 -1 (-1150 1450)(-950 1450);
WIRE 16 -1 (-1150 1350)(-1150 1400);
WIRE 16 -1 (-1150 1400)(-950 1400);
WIRE 16 -1 (-1150 1300)(-1150 1350);
WIRE 16 -1 (-1150 1350)(-950 1350);
WIRE 16 -1 (-1150 1250)(-1150 1300);
WIRE 16 -1 (-1150 1300)(-950 1300);
WIRE 16 -1 (-1150 1200)(-1150 1250);
WIRE 16 -1 (-1150 1250)(-950 1250);
WIRE 16 -1 (-1150 1150)(-1150 1200);
WIRE 16 -1 (-1150 1200)(-950 1200);
WIRE 16 -1 (-1150 1150)(-950 1150);
WIRE 16 -1 (-1300 2650)(-1300 2550);
WIRE 16 -1 (-1300 2550)(-1150 2550);
WIRE 16 -1 (-1150 2500)(-1150 2550);
WIRE 16 -1 (-1150 2550)(-950 2550);
WIRE 16 -1 (-1150 2500)(-950 2500);
WIRE 16 -1 (2450 1150)(2450 1250);
WIRE 16 -1 (2450 1250)(2450 1300);
WIRE 16 -1 (2450 1250)(2250 1250);
WIRE 16 -1 (2450 1300)(2450 1350);
WIRE 16 -1 (2450 1300)(2250 1300);
WIRE 16 -1 (2450 1350)(2450 1400);
WIRE 16 -1 (2450 1350)(2250 1350);
WIRE 16 -1 (2450 1400)(2450 1450);
WIRE 16 -1 (2450 1400)(2250 1400);
WIRE 16 -1 (2450 1450)(2450 1500);
WIRE 16 -1 (2450 1450)(2250 1450);
WIRE 16 -1 (2450 1500)(2450 1550);
WIRE 16 -1 (2450 1500)(2250 1500);
WIRE 16 -1 (2450 1550)(2450 1600);
WIRE 16 -1 (2450 1550)(2250 1550);
WIRE 16 -1 (2450 1600)(2450 1650);
WIRE 16 -1 (2450 1600)(2250 1600);
WIRE 16 -1 (2450 1650)(2450 1700);
WIRE 16 -1 (2450 1650)(2250 1650);
WIRE 16 -1 (2450 1700)(2450 1750);
WIRE 16 -1 (2450 1700)(2250 1700);
WIRE 16 -1 (2450 1750)(2450 1800);
WIRE 16 -1 (2450 1750)(2250 1750);
WIRE 16 -1 (2450 1800)(2450 1850);
WIRE 16 -1 (2450 1800)(2250 1800);
WIRE 16 -1 (2450 1850)(2450 1900);
WIRE 16 -1 (2450 1850)(2250 1850);
WIRE 16 -1 (2450 1900)(2450 1950);
WIRE 16 -1 (2450 1900)(2250 1900);
WIRE 16 -1 (2450 1950)(2450 2000);
WIRE 16 -1 (2450 1950)(2250 1950);
WIRE 16 -1 (2450 2000)(2450 2050);
WIRE 16 -1 (2450 2000)(2250 2000);
WIRE 16 -1 (2450 2050)(2450 2100);
WIRE 16 -1 (2450 2050)(2250 2050);
WIRE 16 -1 (2450 2100)(2450 2150);
WIRE 16 -1 (2450 2100)(2250 2100);
WIRE 16 -1 (2450 2150)(2450 2200);
WIRE 16 -1 (2450 2150)(2250 2150);
WIRE 16 -1 (2450 2200)(2450 2250);
WIRE 16 -1 (2450 2200)(2250 2200);
WIRE 16 -1 (2450 2250)(2450 2300);
WIRE 16 -1 (2450 2250)(2250 2250);
WIRE 16 -1 (2450 2300)(2450 2350);
WIRE 16 -1 (2450 2300)(2250 2300);
WIRE 16 -1 (2450 2350)(2450 2400);
WIRE 16 -1 (2450 2350)(2250 2350);
WIRE 16 -1 (2450 2400)(2450 2450);
WIRE 16 -1 (2450 2400)(2250 2400);
WIRE 16 -1 (2450 2450)(2450 2500);
WIRE 16 -1 (2450 2450)(2250 2450);
WIRE 16 -1 (2450 2500)(2450 2550);
WIRE 16 -1 (2450 2500)(2250 2500);
WIRE 16 -1 (2450 2550)(2450 2600);
WIRE 16 -1 (2450 2550)(2250 2550);
WIRE 16 -1 (2450 2600)(2450 2650);
WIRE 16 -1 (2450 2600)(2250 2600);
WIRE 16 -1 (2450 2650)(2450 2700);
WIRE 16 -1 (2450 2650)(2250 2650);
WIRE 16 -1 (2450 2700)(2450 2750);
WIRE 16 -1 (2450 2700)(2250 2700);
WIRE 16 -1 (2450 2750)(2450 2800);
WIRE 16 -1 (2450 2750)(2250 2750);
WIRE 16 -1 (2450 2800)(2450 2850);
WIRE 16 -1 (2450 2800)(2250 2800);
WIRE 16 -1 (2450 2850)(2450 2900);
WIRE 16 -1 (2450 2850)(2250 2850);
WIRE 16 -1 (2450 2900)(2450 2950);
WIRE 16 -1 (2450 2900)(2250 2900);
WIRE 16 -1 (2450 2950)(2450 3000);
WIRE 16 -1 (2450 2950)(2250 2950);
WIRE 16 -1 (2450 3000)(2450 3050);
WIRE 16 -1 (2450 3000)(2250 3000);
WIRE 16 -1 (2450 3050)(2450 3100);
WIRE 16 -1 (2450 3050)(2250 3050);
WIRE 16 -1 (2450 3100)(2450 3150);
WIRE 16 -1 (2450 3100)(2250 3100);
WIRE 16 -1 (2450 3150)(2450 3200);
WIRE 16 -1 (2450 3150)(2250 3150);
WIRE 16 -1 (2450 3200)(2450 3250);
WIRE 16 -1 (2450 3200)(2250 3200);
WIRE 16 -1 (2450 3250)(2450 3300);
WIRE 16 -1 (2450 3250)(2250 3250);
WIRE 16 -1 (2450 3300)(2450 3350);
WIRE 16 -1 (2450 3300)(2250 3300);
WIRE 16 -1 (2450 3350)(2450 3400);
WIRE 16 -1 (2450 3350)(2250 3350);
WIRE 16 -1 (2450 3400)(2450 3450);
WIRE 16 -1 (2450 3400)(2250 3400);
WIRE 16 -1 (2450 3450)(2450 3500);
WIRE 16 -1 (2450 3450)(2250 3450);
WIRE 16 -1 (2450 3500)(2450 3550);
WIRE 16 -1 (2450 3500)(2250 3500);
WIRE 16 -1 (2450 3550)(2250 3550);
WIRE 16 -1 (-5200 2050)(-5200 1950);
WIRE 16 -1 (-5200 2050)(-3525 2050);
WIRE 16 -1 (-3525 2050)(-3525 1950);
WIRE 16 -1 (-3525 2050)(-3100 2050);
WIRE 16 -1 (-3100 1950)(-3525 1950);
WIRE 16 -1 (-4600 1450)(-4600 1350);
WIRE 16 -1 (-1150 2950)(-1150 2850);
WIRE 16 -1 (-1150 2800)(-1150 2850);
WIRE 16 -1 (-1150 2850)(-950 2850);
WIRE 16 -1 (-1150 2750)(-1150 2800);
WIRE 16 -1 (-1150 2800)(-950 2800);
WIRE 16 -1 (-1150 2700)(-1150 2750);
WIRE 16 -1 (-1150 2750)(-950 2750);
WIRE 16 -1 (-1150 2650)(-1150 2700);
WIRE 16 -1 (-1150 2700)(-950 2700);
WIRE 16 -1 (-1150 2650)(-950 2650);
WIRE 16 -1 (-5200 2200)(-5200 2100);
WIRE 16 -1 (-5200 2100)(-3425 2100);
WIRE 16 -1 (-3425 2000)(-3425 2100);
WIRE 16 -1 (-3425 2100)(-3100 2100);
WIRE 16 -1 (-3100 2000)(-3425 2000);
WIRE 16 -1 (250 2850)(250 2925);
WIRE 16 -1 (250 2800)(250 2850);
WIRE 16 -1 (50 2850)(250 2850);
WIRE 16 -1 (50 2800)(250 2800);
WIRE 16 -1 (1050 1150)(1050 1250);
WIRE 16 -1 (1050 1250)(1050 1300);
WIRE 16 -1 (1050 1250)(1250 1250);
WIRE 16 -1 (1050 1300)(1050 1350);
WIRE 16 -1 (1050 1300)(1250 1300);
WIRE 16 -1 (1050 1350)(1050 1400);
WIRE 16 -1 (1050 1350)(1250 1350);
WIRE 16 -1 (1050 1400)(1050 1450);
WIRE 16 -1 (1050 1400)(1250 1400);
WIRE 16 -1 (1050 1450)(1050 1500);
WIRE 16 -1 (1050 1450)(1250 1450);
WIRE 16 -1 (1050 1500)(1050 1550);
WIRE 16 -1 (1050 1500)(1250 1500);
WIRE 16 -1 (1050 1550)(1050 1600);
WIRE 16 -1 (1050 1550)(1250 1550);
WIRE 16 -1 (1050 1600)(1050 1650);
WIRE 16 -1 (1050 1600)(1250 1600);
WIRE 16 -1 (1050 1650)(1050 1700);
WIRE 16 -1 (1050 1650)(1250 1650);
WIRE 16 -1 (1050 1700)(1050 1750);
WIRE 16 -1 (1050 1700)(1250 1700);
WIRE 16 -1 (1050 1750)(1050 1800);
WIRE 16 -1 (1050 1750)(1250 1750);
WIRE 16 -1 (1050 1800)(1050 1850);
WIRE 16 -1 (1050 1800)(1250 1800);
WIRE 16 -1 (1050 1850)(1050 1900);
WIRE 16 -1 (1050 1850)(1250 1850);
WIRE 16 -1 (1050 1900)(1050 1950);
WIRE 16 -1 (1050 1900)(1250 1900);
WIRE 16 -1 (1050 1950)(1050 2000);
WIRE 16 -1 (1050 1950)(1250 1950);
WIRE 16 -1 (1050 2000)(1050 2050);
WIRE 16 -1 (1050 2000)(1250 2000);
WIRE 16 -1 (1050 2050)(1050 2100);
WIRE 16 -1 (1050 2050)(1250 2050);
WIRE 16 -1 (1050 2100)(1050 2150);
WIRE 16 -1 (1050 2100)(1250 2100);
WIRE 16 -1 (1050 2150)(1050 2200);
WIRE 16 -1 (1050 2150)(1250 2150);
WIRE 16 -1 (1050 2200)(1050 2250);
WIRE 16 -1 (1050 2200)(1250 2200);
WIRE 16 -1 (1050 2250)(1050 2300);
WIRE 16 -1 (1050 2250)(1250 2250);
WIRE 16 -1 (1050 2300)(1050 2350);
WIRE 16 -1 (1050 2300)(1250 2300);
WIRE 16 -1 (1050 2350)(1050 2400);
WIRE 16 -1 (1050 2350)(1250 2350);
WIRE 16 -1 (1050 2400)(1050 2450);
WIRE 16 -1 (1050 2400)(1250 2400);
WIRE 16 -1 (1050 2450)(1050 2500);
WIRE 16 -1 (1050 2450)(1250 2450);
WIRE 16 -1 (1050 2500)(1050 2550);
WIRE 16 -1 (1050 2500)(1250 2500);
WIRE 16 -1 (1050 2550)(1050 2600);
WIRE 16 -1 (1050 2550)(1250 2550);
WIRE 16 -1 (1050 2600)(1050 2650);
WIRE 16 -1 (1050 2600)(1250 2600);
WIRE 16 -1 (1050 2650)(1050 2700);
WIRE 16 -1 (1050 2650)(1250 2650);
WIRE 16 -1 (1050 2700)(1050 2750);
WIRE 16 -1 (1050 2700)(1250 2700);
WIRE 16 -1 (1050 2750)(1050 2800);
WIRE 16 -1 (1050 2750)(1250 2750);
WIRE 16 -1 (1050 2800)(1050 2850);
WIRE 16 -1 (1050 2800)(1250 2800);
WIRE 16 -1 (1050 2850)(1050 2900);
WIRE 16 -1 (1050 2850)(1250 2850);
WIRE 16 -1 (1050 2900)(1050 2950);
WIRE 16 -1 (1050 2900)(1250 2900);
WIRE 16 -1 (1050 2950)(1050 3000);
WIRE 16 -1 (1050 2950)(1250 2950);
WIRE 16 -1 (1050 3000)(1050 3050);
WIRE 16 -1 (1050 3000)(1250 3000);
WIRE 16 -1 (1050 3050)(1050 3100);
WIRE 16 -1 (1050 3050)(1250 3050);
WIRE 16 -1 (1050 3100)(1050 3150);
WIRE 16 -1 (1050 3100)(1250 3100);
WIRE 16 -1 (1050 3150)(1050 3200);
WIRE 16 -1 (1050 3150)(1250 3150);
WIRE 16 -1 (1050 3200)(1050 3250);
WIRE 16 -1 (1050 3200)(1250 3200);
WIRE 16 -1 (1050 3250)(1050 3300);
WIRE 16 -1 (1050 3250)(1250 3250);
WIRE 16 -1 (1050 3300)(1050 3350);
WIRE 16 -1 (1050 3300)(1250 3300);
WIRE 16 -1 (1050 3350)(1050 3400);
WIRE 16 -1 (1050 3350)(1250 3350);
WIRE 16 -1 (1050 3400)(1050 3450);
WIRE 16 -1 (1050 3400)(1250 3400);
WIRE 16 -1 (1050 3450)(1050 3500);
WIRE 16 -1 (1050 3450)(1250 3450);
WIRE 16 -1 (1050 3500)(1050 3550);
WIRE 16 -1 (1050 3500)(1250 3500);
WIRE 16 -1 (1050 3550)(1250 3550);
WIRE 17 -1 (700 3475)(700 3575);
WIRE 17 -1 (700 3575)(700 3675);
WIRE 17 -1 (700 3675)(700 3775);
WIRE 17 -1 (700 3775)(700 3875);
WIRE 17 -1 (700 3875)(700 3975);
WIRE 17 -1 (700 3975)(700 4075);
WIRE 17 -1 (700 4075)(700 4175);
WIRE 17 -1 (700 4175)(700 4275);
WIRE 17 -1 (700 4275)(700 4375);
WIRE 17 -1 (700 4375)(700 4475);
WIRE 17 -1 (700 4475)(700 4575);
WIRE 17 -1 (700 4575)(700 4675);
WIRE 17 -1 (700 4675)(700 4775);
WIRE 17 -1 (700 4775)(700 4875);
WIRE 17 -1 (700 4875)(700 4975);
WIRE 17 -1 (700 4975)(700 5075);
WIRE 17 -1 (1500 5200)(700 5200);
FORCEPROP 2 LAST SIG_NAME M_H_DQS_DP<17:0>
J 0
(925 5210);
DISPLAY 0.617021 (925 5210);
PAINT ORANGE (925 5210);
WIRE 17 -1 (700 5075)(700 5175);
WIRE 17 -1 (700 5175)(700 5200);
WIRE 17 -1 (900 3425)(900 3525);
WIRE 17 -1 (900 3525)(900 3625);
WIRE 17 -1 (900 3625)(900 3725);
WIRE 17 -1 (1500 5150)(900 5150);
FORCEPROP 2 LAST SIG_NAME M_H_DQS_DN<17:0>
J 0
(925 5160);
DISPLAY 0.617021 (925 5160);
PAINT ORANGE (925 5160);
WIRE 17 -1 (900 5125)(900 5150);
WIRE 17 -1 (900 3725)(900 3825);
WIRE 17 -1 (900 3825)(900 3925);
WIRE 17 -1 (900 5025)(900 5125);
WIRE 17 -1 (900 4925)(900 5025);
WIRE 17 -1 (900 3925)(900 4025);
WIRE 17 -1 (900 4025)(900 4125);
WIRE 17 -1 (900 4825)(900 4925);
WIRE 17 -1 (900 4725)(900 4825);
WIRE 17 -1 (900 4125)(900 4225);
WIRE 17 -1 (900 4225)(900 4325);
WIRE 17 -1 (900 4625)(900 4725);
WIRE 17 -1 (900 4525)(900 4625);
WIRE 17 -1 (900 4325)(900 4425);
WIRE 17 -1 (900 4425)(900 4525);
WIRE 17 -1 (-1800 1775)(-1800 1825);
WIRE 17 -1 (-1800 1825)(-1800 1875);
WIRE 17 -1 (-1800 1875)(-1800 1925);
WIRE 17 -1 (-1800 1925)(-1800 1975);
WIRE 17 -1 (-1800 1975)(-1800 2025);
WIRE 17 -1 (-1800 2025)(-1800 2075);
WIRE 17 -1 (-1800 2075)(-1800 2125);
WIRE 17 -1 (-1800 2125)(-1800 2175);
WIRE 17 -1 (-1800 2175)(-1800 2225);
WIRE 17 -1 (-1800 2225)(-1800 2275);
WIRE 17 -1 (-1800 2275)(-1800 2325);
WIRE 17 -1 (-1800 2325)(-1800 2375);
WIRE 17 -1 (-1800 2375)(-1800 2425);
WIRE 17 -1 (-1800 2425)(-1800 2475);
WIRE 17 -1 (-1800 2475)(-1800 2525);
WIRE 17 -1 (-1800 2525)(-1800 2575);
WIRE 17 -1 (-1800 2575)(-1800 2625);
WIRE 17 -1 (-1800 2625)(-1800 2675);
WIRE 17 -1 (-1800 2675)(-1800 2725);
WIRE 17 -1 (-1800 2725)(-1800 2775);
WIRE 17 -1 (-1800 2775)(-1800 2825);
WIRE 17 -1 (-1800 2825)(-1800 2875);
WIRE 17 -1 (-1800 2875)(-1800 2925);
WIRE 17 -1 (-1800 2925)(-1800 2975);
WIRE 17 -1 (-1800 2975)(-1800 3025);
WIRE 17 -1 (-1800 3025)(-1800 3075);
WIRE 17 -1 (-1800 3075)(-1800 3125);
WIRE 17 -1 (-1800 3125)(-1800 3175);
WIRE 17 -1 (-1800 3175)(-1800 3225);
WIRE 17 -1 (-1800 3225)(-1800 3275);
WIRE 17 -1 (-1800 3275)(-1800 3325);
WIRE 17 -1 (-1800 3325)(-1800 3375);
WIRE 17 -1 (-1800 3375)(-1800 3425);
WIRE 17 -1 (-1800 3425)(-1800 3475);
WIRE 17 -1 (-1800 3475)(-1800 3525);
WIRE 17 -1 (-1800 3525)(-1800 3575);
WIRE 17 -1 (-1800 3575)(-1800 3625);
WIRE 17 -1 (-1800 3625)(-1800 3675);
WIRE 17 -1 (-1800 3675)(-1800 3725);
WIRE 17 -1 (-1800 3725)(-1800 3775);
WIRE 17 -1 (-1800 3775)(-1800 3825);
WIRE 17 -1 (-1800 3825)(-1800 3875);
WIRE 17 -1 (-1800 3875)(-1800 3925);
WIRE 17 -1 (-1800 3925)(-1800 3975);
WIRE 17 -1 (-1800 3975)(-1800 4025);
WIRE 17 -1 (-1800 4025)(-1800 4075);
WIRE 17 -1 (-1800 4075)(-1800 4125);
WIRE 17 -1 (-1800 4125)(-1800 4175);
WIRE 17 -1 (-1800 4175)(-1800 4225);
WIRE 17 -1 (-1800 4225)(-1800 4275);
WIRE 17 -1 (-1800 4275)(-1800 4325);
WIRE 17 -1 (-1800 4325)(-1800 4375);
WIRE 17 -1 (-1800 4375)(-1800 4425);
WIRE 17 -1 (-1800 4425)(-1800 4475);
WIRE 17 -1 (-1800 4475)(-1800 4525);
WIRE 17 -1 (-1800 4525)(-1800 4575);
WIRE 17 -1 (-1800 4575)(-1800 4625);
WIRE 17 -1 (-1300 4950)(-1800 4950);
FORCEPROP 2 LAST SIG_NAME M_H_DQ<63:0>
J 0
(-1760 4960);
DISPLAY 0.617021 (-1760 4960);
PAINT ORANGE (-1760 4960);
WIRE 17 -1 (-1800 4925)(-1800 4950);
WIRE 17 -1 (-1800 4625)(-1800 4675);
WIRE 17 -1 (-1800 4675)(-1800 4725);
WIRE 17 -1 (-1800 4875)(-1800 4925);
WIRE 17 -1 (-1800 4825)(-1800 4875);
WIRE 17 -1 (-1800 4725)(-1800 4775);
WIRE 17 -1 (-1800 4775)(-1800 4825);
WIRE 17 -1 (-3400 4075)(-3400 4125);
WIRE 17 -1 (-3400 4125)(-3400 4175);
WIRE 17 -1 (-3400 4175)(-3400 4225);
WIRE 17 -1 (-3400 4225)(-3400 4275);
WIRE 17 -1 (-3400 4275)(-3400 4325);
WIRE 17 -1 (-3400 4325)(-3400 4375);
WIRE 17 -1 (-3400 4375)(-3400 4425);
WIRE 17 -1 (-3400 4425)(-3400 4475);
WIRE 17 -1 (-3400 4475)(-3400 4525);
WIRE 17 -1 (-3400 4525)(-3400 4575);
WIRE 17 -1 (-3400 4575)(-3400 4625);
WIRE 17 -1 (-3400 4625)(-3400 4675);
WIRE 17 -1 (-3400 4675)(-3400 4725);
WIRE 17 -1 (-3400 4725)(-3400 4775);
WIRE 17 -1 (-3400 4775)(-3400 4825);
WIRE 17 -1 (-3950 4950)(-3400 4950);
FORCEPROP 2 LAST SIG_NAME M_H_MA<17:0>
J 0
(-3900 4960);
DISPLAY 0.617021 (-3900 4960);
PAINT ORANGE (-3900 4960);
WIRE 17 -1 (-3400 4925)(-3400 4950);
WIRE 17 -1 (-3400 4825)(-3400 4875);
WIRE 17 -1 (-3400 4875)(-3400 4925);
WIRE 17 -1 (-3400 3925)(-3400 3975);
WIRE 17 -1 (-3400 4000)(-3950 4000);
FORCEPROP 2 LAST SIG_NAME M_H_BA<1:0>
J 0
(-3900 4010);
DISPLAY 0.617021 (-3900 4010);
PAINT ORANGE (-3900 4010);
WIRE 17 -1 (-3400 4000)(-3400 3975);
WIRE 17 -1 (-3400 3825)(-3400 3875);
WIRE 17 -1 (-3400 3900)(-3950 3900);
FORCEPROP 2 LAST SIG_NAME M_H_BG<1:0>
J 0
(-3900 3910);
DISPLAY 0.617021 (-3900 3910);
PAINT ORANGE (-3900 3910);
WIRE 17 -1 (-3400 3900)(-3400 3875);
WIRE 17 -1 (-3400 3625)(-3400 3725);
WIRE 17 -1 (-3400 3750)(-3950 3750);
FORCEPROP 2 LAST SIG_NAME M_H_CLK_DP<3:0>
J 0
(-3900 3760);
DISPLAY 0.617021 (-3900 3760);
PAINT ORANGE (-3900 3760);
WIRE 17 -1 (-3400 3750)(-3400 3725);
WIRE 17 -1 (-3600 3675)(-3600 3575);
WIRE 17 -1 (-3600 3700)(-3950 3700);
FORCEPROP 2 LAST SIG_NAME M_H_CLK_DN<3:0>
J 0
(-3900 3710);
DISPLAY 0.617021 (-3900 3710);
PAINT ORANGE (-3900 3710);
WIRE 17 -1 (-3600 3700)(-3600 3675);
WIRE 17 -1 (-3400 3275)(-3400 3325);
WIRE 17 -1 (-3400 3450)(-3950 3450);
FORCEPROP 2 LAST SIG_NAME M_H_CS_N<7:0>
J 0
(-3925 3460);
DISPLAY 0.617021 (-3925 3460);
PAINT ORANGE (-3925 3460);
WIRE 17 -1 (-3400 3450)(-3400 3425);
WIRE 17 -1 (-3400 3325)(-3400 3375);
WIRE 17 -1 (-3400 3375)(-3400 3425);
WIRE 17 -1 (-3400 3125)(-3400 3175);
WIRE 17 -1 (-3400 3200)(-3950 3200);
FORCEPROP 2 LAST SIG_NAME M_H_CKE<3:0>
J 0
(-3925 3210);
DISPLAY 0.617021 (-3925 3210);
PAINT ORANGE (-3925 3210);
WIRE 17 -1 (-3400 3200)(-3400 3175);
WIRE 17 -1 (-3400 2525)(-3400 2575);
WIRE 17 -1 (-3400 2575)(-3400 2625);
WIRE 17 -1 (-3400 2625)(-3400 2675);
WIRE 17 -1 (-3400 2675)(-3400 2725);
WIRE 17 -1 (-3400 2725)(-3400 2775);
WIRE 17 -1 (-3400 2900)(-3950 2900);
FORCEPROP 2 LAST SIG_NAME M_H_ECC<7:0>
J 0
(-3925 2910);
DISPLAY 0.617021 (-3925 2910);
PAINT ORANGE (-3925 2910);
WIRE 17 -1 (-3400 2900)(-3400 2875);
WIRE 17 -1 (-3400 2775)(-3400 2825);
WIRE 17 -1 (-3400 2825)(-3400 2875);
WIRE 17 -1 (-3400 3050)(-3950 3050);
FORCEPROP 2 LAST SIG_NAME M_H_ODT<3:0>
J 0
(-3925 3060);
DISPLAY 0.617021 (-3925 3060);
PAINT ORANGE (-3925 3060);
WIRE 17 -1 (-3400 3050)(-3400 3025);
WIRE 17 -1 (-3400 2975)(-3400 3025);
WIRE 16 -1 (-1900 4650)(-2100 4650);
WIRE 16 -1 (-1900 4600)(-2100 4600);
WIRE 16 -1 (600 3550)(400 3550);
WIRE 16 -1 (-3950 1650)(-3100 1650);
FORCEPROP 2 LAST SIG_NAME TP_CH_H_DIMM_H0_RFU_2
J 0
(-3900 1660);
DISPLAY 0.617021 (-3900 1660);
PAINT ORANGE (-3900 1660);
FORCEPROP 2 LASTPROP $XRERR UNIQUE?
J 0
(-4190 1650);
DISPLAY 0.638298 (-4190 1650);
PAINT MONO (-4190 1650);
DISPLAY INVISIBLE (-4190 1650);
WIRE 16 -1 (-1900 3400)(-2100 3400);
WIRE 16 -1 (800 4900)(400 4900);
WIRE 16 -1 (-1900 4400)(-2100 4400);
WIRE 16 -1 (-4650 1750)(-4600 1750);
WIRE 16 -1 (-4600 1750)(-4600 1650);
WIRE 16 -1 (-3100 1750)(-4600 1750);
FORCEPROP 2 LAST SIG_NAME M_H_VREF
J 0
(-3900 1760);
DISPLAY 0.617021 (-3900 1760);
PAINT ORANGE (-3900 1760);
WIRE 16 -1 (-3950 1600)(-3100 1600);
FORCEPROP 2 LAST SIG_NAME TP_CH_H_DIMM_H0_RFU_1
J 0
(-3900 1610);
DISPLAY 0.617021 (-3900 1610);
PAINT ORANGE (-3900 1610);
FORCEPROP 2 LASTPROP $XRERR UNIQUE?
J 0
(-4190 1600);
DISPLAY 0.638298 (-4190 1600);
PAINT MONO (-4190 1600);
DISPLAY INVISIBLE (-4190 1600);
WIRE 16 -1 (-3950 1550)(-3100 1550);
FORCEPROP 2 LAST SIG_NAME TP_CH_H_DIMM_H0_RFU_0
J 0
(-3900 1560);
DISPLAY 0.617021 (-3900 1560);
PAINT ORANGE (-3900 1560);
FORCEPROP 2 LASTPROP $XRERR UNIQUE?
J 0
(-4190 1550);
DISPLAY 0.638298 (-4190 1550);
PAINT MONO (-4190 1550);
DISPLAY INVISIBLE (-4190 1550);
WIRE 16 -1 (-3950 1850)(-3100 1850);
FORCEPROP 2 LAST SIG_NAME SMB_DDR_GHJ_VPP_SCL
J 0
(-3910 1860);
DISPLAY 0.617021 (-3910 1860);
PAINT ORANGE (-3910 1860);
WIRE 16 -1 (-3950 1900)(-3100 1900);
WIRE 16 -1 (-3950 1450)(-3100 1450);
FORCEPROP 2 LAST SIG_NAME FM_ADR_COMPLETE_GHJ_N
J 0
(-3900 1460);
DISPLAY 0.617021 (-3900 1460);
PAINT ORANGE (-3900 1460);
WIRE 16 -1 (-3100 2200)(-3950 2200);
FORCEPROP 2 LAST SIG_NAME M_H_ACT_N
J 0
(-3900 2210);
DISPLAY 0.617021 (-3900 2210);
PAINT ORANGE (-3900 2210);
WIRE 16 -1 (-3100 2250)(-3975 2250);
FORCEPROP 2 LAST SIG_NAME M_H_ALERT_N
J 0
(-3925 2260);
DISPLAY 0.617021 (-3925 2260);
PAINT ORANGE (-3925 2260);
WIRE 16 -1 (-3100 2500)(-3300 2500);
WIRE 16 -1 (-3100 2550)(-3300 2550);
WIRE 16 -1 (-3450 2850)(-3950 2850);
FORCEPROP 2 LAST SIG_NAME M_H_PAR
J 0
(-3925 2860);
DISPLAY 0.617021 (-3925 2860);
PAINT ORANGE (-3925 2860);
WIRE 16 -1 (-3100 2400)(-3450 2400);
WIRE 16 -1 (-3450 2400)(-3450 2850);
WIRE 16 -1 (-3550 2600)(-4275 2600);
FORCEPROP 2 LAST SIG_NAME FM_DIMM_EVENT_COD_N
J 0
(-4248 2614);
DISPLAY 0.617021 (-4248 2614);
PAINT ORANGE (-4248 2614);
WIRE 16 -1 (-3550 2300)(-3100 2300);
WIRE 16 -1 (-3550 2300)(-3550 2600);
WIRE 16 -1 (-3500 2800)(-3950 2800);
FORCEPROP 2 LAST SIG_NAME M_GHJ_RST_N
J 0
(-3925 2810);
DISPLAY 0.617021 (-3925 2810);
PAINT ORANGE (-3925 2810);
WIRE 16 -1 (-3100 2350)(-3500 2350);
WIRE 16 -1 (-3500 2350)(-3500 2800);
WIRE 16 -1 (-3100 2600)(-3300 2600);
WIRE 16 -1 (-3100 2650)(-3300 2650);
WIRE 16 -1 (-3100 2700)(-3300 2700);
WIRE 16 -1 (-3100 2750)(-3300 2750);
WIRE 16 -1 (-3100 2800)(-3300 2800);
WIRE 16 -1 (-3100 3000)(-3300 3000);
WIRE 16 -1 (-3100 2950)(-3300 2950);
WIRE 16 -1 (-3100 2850)(-3300 2850);
WIRE 16 -1 (-3100 3550)(-3500 3550);
WIRE 16 -1 (-3100 3250)(-3300 3250);
WIRE 16 -1 (-3100 3100)(-3300 3100);
WIRE 16 -1 (-3100 3150)(-3300 3150);
WIRE 16 -1 (-3100 3300)(-3300 3300);
WIRE 16 -1 (-3300 3500)(-3950 3500);
FORCEPROP 2 LAST SIG_NAME M_H_C<2>
J 0
(-3925 3510);
DISPLAY 0.617021 (-3925 3510);
PAINT ORANGE (-3925 3510);
WIRE 16 -1 (-3300 3500)(-3300 3450);
WIRE 16 -1 (-3300 3450)(-3100 3450);
WIRE 16 -1 (-3100 3400)(-3300 3400);
WIRE 16 -1 (-3100 3350)(-3300 3350);
WIRE 16 -1 (-3100 3650)(-3500 3650);
WIRE 16 -1 (-3100 3800)(-3300 3800);
WIRE 16 -1 (-3100 3600)(-3300 3600);
WIRE 16 -1 (-3100 3700)(-3300 3700);
WIRE 16 -1 (-3100 3900)(-3300 3900);
WIRE 16 -1 (-3100 3850)(-3300 3850);
WIRE 16 -1 (-3100 4050)(-3300 4050);
WIRE 16 -1 (-3100 3950)(-3300 3950);
WIRE 16 -1 (-1900 1950)(-2100 1950);
WIRE 16 -1 (-1900 1900)(-2100 1900);
WIRE 16 -1 (-1900 1850)(-2100 1850);
WIRE 16 -1 (-1900 2600)(-2100 2600);
WIRE 16 -1 (-1900 2500)(-2100 2500);
WIRE 16 -1 (-1900 3050)(-2100 3050);
WIRE 16 -1 (-1900 3100)(-2100 3100);
WIRE 16 -1 (-1900 3650)(-2100 3650);
WIRE 16 -1 (-1900 3550)(-2100 3550);
WIRE 16 -1 (-1900 3500)(-2100 3500);
WIRE 16 -1 (-1900 1750)(-2100 1750);
WIRE 16 -1 (-1900 1800)(-2100 1800);
WIRE 16 -1 (-1900 2050)(-2100 2050);
WIRE 16 -1 (-1900 2200)(-2100 2200);
WIRE 16 -1 (-1900 2300)(-2100 2300);
WIRE 16 -1 (-1900 2350)(-2100 2350);
WIRE 16 -1 (-1900 2400)(-2100 2400);
WIRE 16 -1 (-1900 2450)(-2100 2450);
WIRE 16 -1 (-1900 2550)(-2100 2550);
WIRE 16 -1 (-1900 2650)(-2100 2650);
WIRE 16 -1 (-1900 2750)(-2100 2750);
WIRE 16 -1 (-1900 2800)(-2100 2800);
WIRE 16 -1 (-1900 2850)(-2100 2850);
WIRE 16 -1 (-1900 2900)(-2100 2900);
WIRE 16 -1 (-1900 2950)(-2100 2950);
WIRE 16 -1 (-1900 3000)(-2100 3000);
WIRE 16 -1 (-1900 3250)(-2100 3250);
WIRE 16 -1 (-1900 3300)(-2100 3300);
WIRE 16 -1 (-1900 3350)(-2100 3350);
WIRE 16 -1 (-1900 3450)(-2100 3450);
WIRE 16 -1 (-1900 3600)(-2100 3600);
WIRE 16 -1 (-1900 3700)(-2100 3700);
WIRE 16 -1 (-1900 3750)(-2100 3750);
WIRE 16 -1 (-1900 3800)(-2100 3800);
WIRE 16 -1 (-1900 3850)(-2100 3850);
WIRE 16 -1 (-1900 3900)(-2100 3900);
WIRE 16 -1 (-1900 3950)(-2100 3950);
WIRE 16 -1 (-1900 4000)(-2100 4000);
WIRE 16 -1 (-1900 4050)(-2100 4050);
WIRE 16 -1 (-1900 3150)(-2100 3150);
WIRE 16 -1 (-1900 3200)(-2100 3200);
WIRE 16 -1 (-1900 2000)(-2100 2000);
WIRE 16 -1 (-1900 2100)(-2100 2100);
WIRE 16 -1 (-1900 2250)(-2100 2250);
WIRE 16 -1 (-1900 2150)(-2100 2150);
WIRE 16 -1 (-1900 2700)(-2100 2700);
WIRE 16 -1 (-3100 4150)(-3300 4150);
WIRE 16 -1 (-3100 4350)(-3300 4350);
WIRE 16 -1 (-3100 4300)(-3300 4300);
WIRE 16 -1 (-3100 4250)(-3300 4250);
WIRE 16 -1 (-3100 4200)(-3300 4200);
WIRE 16 -1 (-3100 4100)(-3300 4100);
WIRE 16 -1 (-3100 4600)(-3300 4600);
WIRE 16 -1 (-3100 4550)(-3300 4550);
WIRE 16 -1 (-3100 4500)(-3300 4500);
WIRE 16 -1 (-3100 4450)(-3300 4450);
WIRE 16 -1 (-3100 4400)(-3300 4400);
WIRE 16 -1 (-3100 4850)(-3300 4850);
WIRE 16 -1 (-3100 4800)(-3300 4800);
WIRE 16 -1 (-3100 4750)(-3300 4750);
WIRE 16 -1 (-3100 4700)(-3300 4700);
WIRE 16 -1 (-3100 4650)(-3300 4650);
WIRE 16 -1 (-3100 4900)(-3300 4900);
WIRE 16 -1 (-1900 4900)(-2100 4900);
WIRE 16 -1 (-1900 4850)(-2100 4850);
WIRE 16 -1 (-1900 4800)(-2100 4800);
WIRE 16 -1 (-1900 4100)(-2100 4100);
WIRE 16 -1 (-1900 4150)(-2100 4150);
WIRE 16 -1 (-1900 4200)(-2100 4200);
WIRE 16 -1 (-1900 4250)(-2100 4250);
WIRE 16 -1 (-1900 4300)(-2100 4300);
WIRE 16 -1 (-1900 4350)(-2100 4350);
WIRE 16 -1 (-1900 4450)(-2100 4450);
WIRE 16 -1 (-1900 4500)(-2100 4500);
WIRE 16 -1 (-1900 4550)(-2100 4550);
WIRE 16 -1 (-1900 4700)(-2100 4700);
WIRE 16 -1 (-1900 4750)(-2100 4750);
WIRE 16 -1 (600 4050)(400 4050);
WIRE 16 -1 (800 4000)(400 4000);
WIRE 16 -1 (600 3950)(400 3950);
WIRE 16 -1 (800 3900)(400 3900);
WIRE 16 -1 (600 3850)(400 3850);
WIRE 16 -1 (800 3800)(400 3800);
WIRE 16 -1 (600 3750)(400 3750);
WIRE 16 -1 (800 3700)(400 3700);
WIRE 16 -1 (600 3650)(400 3650);
WIRE 16 -1 (800 3600)(400 3600);
WIRE 16 -1 (800 3500)(400 3500);
WIRE 16 -1 (600 3450)(400 3450);
WIRE 16 -1 (800 3400)(400 3400);
WIRE 16 -1 (600 4350)(400 4350);
WIRE 16 -1 (800 4300)(400 4300);
WIRE 16 -1 (600 4250)(400 4250);
WIRE 16 -1 (800 4200)(400 4200);
WIRE 16 -1 (600 4150)(400 4150);
WIRE 16 -1 (800 4100)(400 4100);
WIRE 16 -1 (800 5100)(400 5100);
WIRE 16 -1 (600 5050)(400 5050);
WIRE 16 -1 (800 5000)(400 5000);
WIRE 16 -1 (600 4950)(400 4950);
WIRE 16 -1 (600 4850)(400 4850);
WIRE 16 -1 (800 4800)(400 4800);
WIRE 16 -1 (600 4750)(400 4750);
WIRE 16 -1 (800 4700)(400 4700);
WIRE 16 -1 (600 4650)(400 4650);
WIRE 16 -1 (800 4600)(400 4600);
WIRE 16 -1 (600 4550)(400 4550);
WIRE 16 -1 (800 4500)(400 4500);
WIRE 16 -1 (600 4450)(400 4450);
WIRE 16 -1 (800 4400)(400 4400);
WIRE 16 -1 (600 5150)(400 5150);
DOT 1 (1050 3250);
DOT 1 (250 2850);
DOT 1 (1050 2850);
DOT 1 (1050 3150);
DOT 1 (-1150 2350);
DOT 1 (-1150 2550);
DOT 1 (-1150 1250);
DOT 1 (-1150 1300);
DOT 1 (-1150 1350);
DOT 1 (-1150 1400);
DOT 1 (-1150 1450);
DOT 1 (-1150 1500);
DOT 1 (-1150 1550);
DOT 1 (-1150 1200);
DOT 1 (-1150 1600);
DOT 1 (-1150 1650);
DOT 1 (-1150 1750);
DOT 1 (-1150 1700);
DOT 1 (-1150 1800);
DOT 1 (-1150 1850);
DOT 1 (-1150 1900);
DOT 1 (-1150 1950);
DOT 1 (-1150 2000);
DOT 1 (-1150 2050);
DOT 1 (-1150 2100);
DOT 1 (-1150 2200);
DOT 1 (-1150 2250);
DOT 1 (-1150 2300);
DOT 1 (-1150 2400);
DOT 1 (-1150 2800);
DOT 1 (-1150 2850);
DOT 1 (-4600 1750);
DOT 1 (1050 1350);
DOT 1 (1050 1300);
DOT 1 (1050 1250);
DOT 1 (1050 1400);
DOT 1 (1050 1450);
DOT 1 (1050 1600);
DOT 1 (1050 1500);
DOT 1 (1050 1550);
DOT 1 (1050 1650);
DOT 1 (1050 1700);
DOT 1 (1050 1750);
DOT 1 (1050 1800);
DOT 1 (1050 1950);
DOT 1 (1050 1900);
DOT 1 (1050 2000);
DOT 1 (1050 2050);
DOT 1 (1050 2200);
DOT 1 (1050 2250);
DOT 1 (1050 2100);
DOT 1 (1050 2150);
DOT 1 (1050 2350);
DOT 1 (1050 2300);
DOT 1 (1050 2500);
DOT 1 (1050 2450);
DOT 1 (1050 2400);
DOT 1 (1050 2700);
DOT 1 (1050 3000);
DOT 1 (1050 2950);
DOT 1 (1050 2900);
DOT 1 (1050 3100);
DOT 1 (1050 3050);
DOT 1 (1050 3200);
DOT 1 (1050 3400);
DOT 1 (1050 3350);
DOT 1 (1050 3450);
DOT 1 (1050 3300);
DOT 1 (1050 3500);
DOT 1 (2450 3500);
DOT 1 (2450 3300);
DOT 1 (2450 3450);
DOT 1 (2450 3350);
DOT 1 (2450 3400);
DOT 1 (2450 3150);
DOT 1 (2450 3200);
DOT 1 (2450 3250);
DOT 1 (2450 3050);
DOT 1 (2450 3100);
DOT 1 (2450 2900);
DOT 1 (2450 2950);
DOT 1 (2450 3000);
DOT 1 (2450 2800);
DOT 1 (2450 2850);
DOT 1 (2450 2650);
DOT 1 (2450 2750);
DOT 1 (2450 2700);
DOT 1 (2450 2550);
DOT 1 (2450 2600);
DOT 1 (2450 2400);
DOT 1 (2450 2450);
DOT 1 (2450 2500);
DOT 1 (2450 2300);
DOT 1 (2450 2350);
DOT 1 (2450 2150);
DOT 1 (2450 2100);
DOT 1 (2450 2250);
DOT 1 (2450 2200);
DOT 1 (2450 2050);
DOT 1 (2450 2000);
DOT 1 (2450 1900);
DOT 1 (2450 1950);
DOT 1 (2450 1800);
DOT 1 (2450 1850);
DOT 1 (2450 1750);
DOT 1 (2450 1700);
DOT 1 (2450 1650);
DOT 1 (2450 1550);
DOT 1 (2450 1500);
DOT 1 (2450 1600);
DOT 1 (2450 1450);
DOT 1 (2450 1400);
DOT 1 (2450 1250);
DOT 1 (2450 1300);
DOT 1 (2450 1350);
DOT 1 (1050 2800);
DOT 1 (1050 2750);
DOT 1 (1050 2650);
DOT 1 (1050 2600);
DOT 1 (1050 2550);
DOT 1 (-1150 2700);
DOT 1 (-3425 2100);
DOT 1 (-3525 2050);
DOT 1 (-1150 2150);
DOT 1 (-1150 2750);
DOT 1 (1050 1850);
FORCENOTE
PVDDQ (SINGLE SIDE) CAP: 10UF X1, 22UF X50
(-3000 5250) 0;
DISPLAY LEFT (-3000 5250);
DISPLAY 1.021277 (-3000 5250);
PAINT PURPLE (-3000 5250);
FORCENOTE
PVDDQ (DOUBLE SIDE) CAP: 100UF X8, 47UF X41
(-3000 5200) 0;
DISPLAY LEFT (-3000 5200);
DISPLAY 1.021277 (-3000 5200);
PAINT PURPLE (-3000 5200);
FORCENOTE
PVTT CAP: 100UF X2, 47UF X1
(-3000 5300) 0;
DISPLAY LEFT (-3000 5300);
DISPLAY 1.021277 (-3000 5300);
PAINT PURPLE (-3000 5300);
FORCENOTE
PLACE CAP NEAR DIMM CONNECTOR
(-5188 1127) 0;
DISPLAY LEFT (-5188 1127);
DISPLAY 1.574468 (-5188 1127);
PAINT PURPLE (-5188 1127);
FORCENOTE
SMBUS ADDR: 0XA4
(-5275 725) 0;
DISPLAY LEFT (-5275 725);
DISPLAY 1.957447 (-5275 725);
PAINT PURPLE (-5275 725);
FORCENOTE
PVPP CAP: 10UF X12
(-3000 5350) 0;
DISPLAY LEFT (-3000 5350);
DISPLAY 1.021277 (-3000 5350);
PAINT PURPLE (-3000 5350);
FORCENOTE
CAP BETWEEN DIMM
(-3000 5425) 0;
DISPLAY LEFT (-3000 5425);
DISPLAY 1.276596 (-3000 5425);
PAINT PURPLE (-3000 5425);
QUIT
